(kicad_sch
	(version 20250114)
	(generator "eeschema")
	(generator_version "9.0")
	(paper "A3")
	(title_block
		(title "Kintex 410T devboard")
		(date "2024-04-03")
		(rev "1.1.2")
	)
	(text "DIP SWITCH"
		(exclude_from_sim no)
		(at 211.455 227.965 0)
		(effects
			(font
				(size 1.27 1.27)
				(thickness 0.5994)
				(bold yes)
			)
			(justify left bottom)
		)
	)
	(text "GPIO Headers"
		(exclude_from_sim no)
		(at 210.82 138.43 0)
		(effects
			(font
				(size 1.27 1.27)
				(thickness 0.5994)
				(bold yes)
			)
			(justify left bottom)
		)
	)
	(text "LEDs"
		(exclude_from_sim no)
		(at 13.335 139.065 0)
		(effects
			(font
				(size 1.27 1.27)
				(thickness 0.5994)
				(bold yes)
			)
			(justify left bottom)
		)
	)
	(text "FANs"
		(exclude_from_sim no)
		(at 13.97 240.03 0)
		(effects
			(font
				(size 1.27 1.27)
				(thickness 0.5994)
				(bold yes)
			)
			(justify left bottom)
		)
	)
	(text "A"
		(exclude_from_sim no)
		(at 57.15 22.86 0)
		(effects
			(font
				(size 1.27 1.27)
				(thickness 0.3)
				(bold yes)
			)
			(justify left bottom)
		)
	)
	(text "PMODs"
		(exclude_from_sim no)
		(at 13.335 17.145 0)
		(effects
			(font
				(size 1.27 1.27)
				(thickness 0.5994)
				(bold yes)
			)
			(justify left bottom)
		)
	)
	(text "BUTTONs"
		(exclude_from_sim no)
		(at 210.82 74.93 0)
		(effects
			(font
				(size 1.27 1.27)
				(thickness 0.5994)
				(bold yes)
			)
			(justify left bottom)
		)
	)
	(text "B"
		(exclude_from_sim no)
		(at 57.15 80.01 0)
		(effects
			(font
				(size 1.27 1.27)
				(thickness 0.3)
				(bold yes)
			)
			(justify left bottom)
		)
	)
	(text "ChipWhisperer connector"
		(exclude_from_sim no)
		(at 210.82 17.145 0)
		(effects
			(font
				(size 1.27 1.27)
				(thickness 0.5994)
				(bold yes)
			)
			(justify left bottom)
		)
	)
	(junction
		(at 179.07 182.88)
		(diameter 0)
		(color 0 0 0 0)
	)
	(junction
		(at 276.86 182.88)
		(diameter 0)
		(color 0 0 0 0)
	)
	(junction
		(at 365.76 182.88)
		(diameter 0)
		(color 0 0 0 0)
	)
	(junction
		(at 223.52 267.97)
		(diameter 0)
		(color 0 0 0 0)
	)
	(junction
		(at 105.41 267.97)
		(diameter 0)
		(color 0 0 0 0)
	)
	(junction
		(at 179.07 163.83)
		(diameter 0)
		(color 0 0 0 0)
	)
	(junction
		(at 58.42 83.82)
		(diameter 0)
		(color 0 0 0 0)
	)
	(junction
		(at 287.02 110.49)
		(diameter 0)
		(color 0 0 0 0)
	)
	(junction
		(at 276.86 200.66)
		(diameter 0)
		(color 0 0 0 0)
	)
	(junction
		(at 223.52 273.05)
		(diameter 0)
		(color 0 0 0 0)
	)
	(junction
		(at 96.52 260.35)
		(diameter 0)
		(color 0 0 0 0)
	)
	(junction
		(at 68.58 273.05)
		(diameter 0)
		(color 0 0 0 0)
	)
	(junction
		(at 223.52 257.81)
		(diameter 0)
		(color 0 0 0 0)
	)
	(junction
		(at 276.86 167.64)
		(diameter 0)
		(color 0 0 0 0)
	)
	(junction
		(at 361.95 110.49)
		(diameter 0)
		(color 0 0 0 0)
	)
	(junction
		(at 111.76 109.22)
		(diameter 0)
		(color 0 0 0 0)
	)
	(junction
		(at 124.46 267.97)
		(diameter 0)
		(color 0 0 0 0)
	)
	(junction
		(at 129.54 242.57)
		(diameter 0)
		(color 0 0 0 0)
	)
	(junction
		(at 76.2 242.57)
		(diameter 0)
		(color 0 0 0 0)
	)
	(junction
		(at 86.36 242.57)
		(diameter 0)
		(color 0 0 0 0)
	)
	(junction
		(at 295.91 262.89)
		(diameter 0)
		(color 0 0 0 0)
	)
	(junction
		(at 302.26 91.44)
		(diameter 0)
		(color 0 0 0 0)
	)
	(junction
		(at 223.52 262.89)
		(diameter 0)
		(color 0 0 0 0)
	)
	(junction
		(at 295.91 278.13)
		(diameter 0)
		(color 0 0 0 0)
	)
	(junction
		(at 179.07 260.35)
		(diameter 0)
		(color 0 0 0 0)
	)
	(junction
		(at 57.15 26.67)
		(diameter 0)
		(color 0 0 0 0)
	)
	(junction
		(at 365.76 162.56)
		(diameter 0)
		(color 0 0 0 0)
	)
	(junction
		(at 295.91 275.59)
		(diameter 0)
		(color 0 0 0 0)
	)
	(junction
		(at 223.52 265.43)
		(diameter 0)
		(color 0 0 0 0)
	)
	(junction
		(at 276.86 165.1)
		(diameter 0)
		(color 0 0 0 0)
	)
	(junction
		(at 306.07 113.03)
		(diameter 0)
		(color 0 0 0 0)
	)
	(junction
		(at 295.91 273.05)
		(diameter 0)
		(color 0 0 0 0)
	)
	(junction
		(at 223.52 260.35)
		(diameter 0)
		(color 0 0 0 0)
	)
	(junction
		(at 309.88 91.44)
		(diameter 0)
		(color 0 0 0 0)
	)
	(junction
		(at 43.18 142.24)
		(diameter 0)
		(color 0 0 0 0)
	)
	(junction
		(at 365.76 200.66)
		(diameter 0)
		(color 0 0 0 0)
	)
	(junction
		(at 328.93 93.98)
		(diameter 0)
		(color 0 0 0 0)
	)
	(junction
		(at 381 113.03)
		(diameter 0)
		(color 0 0 0 0)
	)
	(junction
		(at 295.91 270.51)
		(diameter 0)
		(color 0 0 0 0)
	)
	(junction
		(at 276.86 170.18)
		(diameter 0)
		(color 0 0 0 0)
	)
	(junction
		(at 384.81 91.44)
		(diameter 0)
		(color 0 0 0 0)
	)
	(junction
		(at 259.08 74.93)
		(diameter 0)
		(color 0 0 0 0)
	)
	(junction
		(at 68.58 280.67)
		(diameter 0)
		(color 0 0 0 0)
	)
	(junction
		(at 96.52 219.71)
		(diameter 0)
		(color 0 0 0 0)
	)
	(junction
		(at 179.07 219.71)
		(diameter 0)
		(color 0 0 0 0)
	)
	(junction
		(at 295.91 265.43)
		(diameter 0)
		(color 0 0 0 0)
	)
	(junction
		(at 246.38 149.86)
		(diameter 0)
		(color 0 0 0 0)
	)
	(junction
		(at 245.11 25.4)
		(diameter 0)
		(color 0 0 0 0)
	)
	(junction
		(at 96.52 182.88)
		(diameter 0)
		(color 0 0 0 0)
	)
	(junction
		(at 179.07 201.93)
		(diameter 0)
		(color 0 0 0 0)
	)
	(junction
		(at 276.86 162.56)
		(diameter 0)
		(color 0 0 0 0)
	)
	(junction
		(at 138.43 260.35)
		(diameter 0)
		(color 0 0 0 0)
	)
	(junction
		(at 223.52 270.51)
		(diameter 0)
		(color 0 0 0 0)
	)
	(junction
		(at 405.13 93.98)
		(diameter 0)
		(color 0 0 0 0)
	)
	(junction
		(at 377.19 91.44)
		(diameter 0)
		(color 0 0 0 0)
	)
	(junction
		(at 170.18 242.57)
		(diameter 0)
		(color 0 0 0 0)
	)
	(junction
		(at 72.39 242.57)
		(diameter 0)
		(color 0 0 0 0)
	)
	(junction
		(at 279.4 110.49)
		(diameter 0)
		(color 0 0 0 0)
	)
	(junction
		(at 354.33 110.49)
		(diameter 0)
		(color 0 0 0 0)
	)
	(junction
		(at 295.91 260.35)
		(diameter 0)
		(color 0 0 0 0)
	)
	(junction
		(at 295.91 267.97)
		(diameter 0)
		(color 0 0 0 0)
	)
	(junction
		(at 306.07 53.34)
		(diameter 0)
		(color 0 0 0 0)
	)
	(junction
		(at 96.52 201.93)
		(diameter 0)
		(color 0 0 0 0)
	)
	(junction
		(at 111.76 52.07)
		(diameter 0)
		(color 0 0 0 0)
	)
	(junction
		(at 335.28 149.86)
		(diameter 0)
		(color 0 0 0 0)
	)
	(junction
		(at 96.52 163.83)
		(diameter 0)
		(color 0 0 0 0)
	)
	(no_connect
		(at 317.5 53.34)
	)
	(no_connect
		(at 97.79 255.27)
	)
	(no_connect
		(at 307.34 33.02)
	)
	(no_connect
		(at 317.5 50.8)
	)
	(no_connect
		(at 139.7 255.27)
	)
	(no_connect
		(at 180.34 255.27)
	)
	(no_connect
		(at 307.34 30.48)
	)
	(bus_entry
		(at 57.15 36.83)
		(size 1.27 1.27)
		(stroke
			(width 0)
			(type default)
		)
	)
	(bus_entry
		(at 246.38 207.01)
		(size 1.27 1.27)
		(stroke
			(width 0)
			(type default)
		)
	)
	(bus_entry
		(at 166.37 91.44)
		(size -1.27 1.27)
		(stroke
			(width 0)
			(type default)
		)
	)
	(bus_entry
		(at 125.73 200.66)
		(size 1.27 1.27)
		(stroke
			(width 0)
			(type default)
		)
	)
	(bus_entry
		(at 58.42 86.36)
		(size 1.27 1.27)
		(stroke
			(width 0)
			(type default)
		)
	)
	(bus_entry
		(at 57.15 29.21)
		(size 1.27 1.27)
		(stroke
			(width 0)
			(type default)
		)
	)
	(bus_entry
		(at 125.73 162.56)
		(size 1.27 1.27)
		(stroke
			(width 0)
			(type default)
		)
	)
	(bus_entry
		(at 335.28 161.29)
		(size 1.27 1.27)
		(stroke
			(width 0)
			(type default)
		)
	)
	(bus_entry
		(at 382.27 186.69)
		(size -1.27 1.27)
		(stroke
			(width 0)
			(type default)
		)
	)
	(bus_entry
		(at 255.27 274.32)
		(size -1.27 1.27)
		(stroke
			(width 0)
			(type default)
		)
	)
	(bus_entry
		(at 255.27 269.24)
		(size 1.27 1.27)
		(stroke
			(width 0)
			(type default)
		)
	)
	(bus_entry
		(at 246.38 161.29)
		(size 1.27 1.27)
		(stroke
			(width 0)
			(type default)
		)
	)
	(bus_entry
		(at 382.27 189.23)
		(size -1.27 1.27)
		(stroke
			(width 0)
			(type default)
		)
	)
	(bus_entry
		(at 255.27 261.62)
		(size -1.27 1.27)
		(stroke
			(width 0)
			(type default)
		)
	)
	(bus_entry
		(at 246.38 199.39)
		(size 1.27 1.27)
		(stroke
			(width 0)
			(type default)
		)
	)
	(bus_entry
		(at 293.37 207.01)
		(size -1.27 1.27)
		(stroke
			(width 0)
			(type default)
		)
	)
	(bus_entry
		(at 165.1 36.83)
		(size -1.27 1.27)
		(stroke
			(width 0)
			(type default)
		)
	)
	(bus_entry
		(at 311.15 237.49)
		(size 1.27 1.27)
		(stroke
			(width 0)
			(type default)
		)
	)
	(bus_entry
		(at 335.28 186.69)
		(size 1.27 1.27)
		(stroke
			(width 0)
			(type default)
		)
	)
	(bus_entry
		(at 57.15 31.75)
		(size 1.27 1.27)
		(stroke
			(width 0)
			(type default)
		)
	)
	(bus_entry
		(at 335.28 196.85)
		(size 1.27 1.27)
		(stroke
			(width 0)
			(type default)
		)
	)
	(bus_entry
		(at 293.37 201.93)
		(size -1.27 1.27)
		(stroke
			(width 0)
			(type default)
		)
	)
	(bus_entry
		(at 382.27 176.53)
		(size -1.27 1.27)
		(stroke
			(width 0)
			(type default)
		)
	)
	(bus_entry
		(at 293.37 196.85)
		(size -1.27 1.27)
		(stroke
			(width 0)
			(type default)
		)
	)
	(bus_entry
		(at 265.43 237.49)
		(size 1.27 1.27)
		(stroke
			(width 0)
			(type default)
		)
	)
	(bus_entry
		(at 293.37 189.23)
		(size -1.27 1.27)
		(stroke
			(width 0)
			(type default)
		)
	)
	(bus_entry
		(at 335.28 189.23)
		(size 1.27 1.27)
		(stroke
			(width 0)
			(type default)
		)
	)
	(bus_entry
		(at 293.37 207.01)
		(size -1.27 1.27)
		(stroke
			(width 0)
			(type default)
		)
	)
	(bus_entry
		(at 335.28 179.07)
		(size 1.27 1.27)
		(stroke
			(width 0)
			(type default)
		)
	)
	(bus_entry
		(at 255.27 264.16)
		(size -1.27 1.27)
		(stroke
			(width 0)
			(type default)
		)
	)
	(bus_entry
		(at 293.37 176.53)
		(size -1.27 1.27)
		(stroke
			(width 0)
			(type default)
		)
	)
	(bus_entry
		(at 165.1 31.75)
		(size -1.27 1.27)
		(stroke
			(width 0)
			(type default)
		)
	)
	(bus_entry
		(at 255.27 271.78)
		(size 1.27 1.27)
		(stroke
			(width 0)
			(type default)
		)
	)
	(bus_entry
		(at 246.38 179.07)
		(size 1.27 1.27)
		(stroke
			(width 0)
			(type default)
		)
	)
	(bus_entry
		(at 246.38 201.93)
		(size 1.27 1.27)
		(stroke
			(width 0)
			(type default)
		)
	)
	(bus_entry
		(at 255.27 264.16)
		(size 1.27 1.27)
		(stroke
			(width 0)
			(type default)
		)
	)
	(bus_entry
		(at 125.73 218.44)
		(size 1.27 1.27)
		(stroke
			(width 0)
			(type default)
		)
	)
	(bus_entry
		(at 335.28 181.61)
		(size 1.27 1.27)
		(stroke
			(width 0)
			(type default)
		)
	)
	(bus_entry
		(at 245.11 34.29)
		(size 1.27 1.27)
		(stroke
			(width 0)
			(type default)
		)
	)
	(bus_entry
		(at 246.38 194.31)
		(size 1.27 1.27)
		(stroke
			(width 0)
			(type default)
		)
	)
	(bus_entry
		(at 246.38 173.99)
		(size 1.27 1.27)
		(stroke
			(width 0)
			(type default)
		)
	)
	(bus_entry
		(at 246.38 171.45)
		(size 1.27 1.27)
		(stroke
			(width 0)
			(type default)
		)
	)
	(bus_entry
		(at 246.38 163.83)
		(size 1.27 1.27)
		(stroke
			(width 0)
			(type default)
		)
	)
	(bus_entry
		(at 311.15 232.41)
		(size 1.27 1.27)
		(stroke
			(width 0)
			(type default)
		)
	)
	(bus_entry
		(at 255.27 259.08)
		(size 1.27 1.27)
		(stroke
			(width 0)
			(type default)
		)
	)
	(bus_entry
		(at 334.01 109.22)
		(size 1.27 1.27)
		(stroke
			(width 0)
			(type default)
		)
	)
	(bus_entry
		(at 335.28 158.75)
		(size 1.27 1.27)
		(stroke
			(width 0)
			(type default)
		)
	)
	(bus_entry
		(at 57.15 34.29)
		(size 1.27 1.27)
		(stroke
			(width 0)
			(type default)
		)
	)
	(bus_entry
		(at 246.38 176.53)
		(size 1.27 1.27)
		(stroke
			(width 0)
			(type default)
		)
	)
	(bus_entry
		(at 311.15 234.95)
		(size 1.27 1.27)
		(stroke
			(width 0)
			(type default)
		)
	)
	(bus_entry
		(at 246.38 191.77)
		(size 1.27 1.27)
		(stroke
			(width 0)
			(type default)
		)
	)
	(bus_entry
		(at 246.38 186.69)
		(size 1.27 1.27)
		(stroke
			(width 0)
			(type default)
		)
	)
	(bus_entry
		(at 255.27 259.08)
		(size -1.27 1.27)
		(stroke
			(width 0)
			(type default)
		)
	)
	(bus_entry
		(at 246.38 204.47)
		(size 1.27 1.27)
		(stroke
			(width 0)
			(type default)
		)
	)
	(bus_entry
		(at 166.37 86.36)
		(size -1.27 1.27)
		(stroke
			(width 0)
			(type default)
		)
	)
	(bus_entry
		(at 166.37 88.9)
		(size -1.27 1.27)
		(stroke
			(width 0)
			(type default)
		)
	)
	(bus_entry
		(at 382.27 168.91)
		(size -1.27 1.27)
		(stroke
			(width 0)
			(type default)
		)
	)
	(bus_entry
		(at 246.38 158.75)
		(size 1.27 1.27)
		(stroke
			(width 0)
			(type default)
		)
	)
	(bus_entry
		(at 335.28 191.77)
		(size 1.27 1.27)
		(stroke
			(width 0)
			(type default)
		)
	)
	(bus_entry
		(at 265.43 232.41)
		(size 1.27 1.27)
		(stroke
			(width 0)
			(type default)
		)
	)
	(bus_entry
		(at 165.1 29.21)
		(size -1.27 1.27)
		(stroke
			(width 0)
			(type default)
		)
	)
	(bus_entry
		(at 384.81 44.45)
		(size -1.27 1.27)
		(stroke
			(width 0)
			(type default)
		)
	)
	(bus_entry
		(at 245.11 39.37)
		(size 1.27 1.27)
		(stroke
			(width 0)
			(type default)
		)
	)
	(bus_entry
		(at 245.11 41.91)
		(size 1.27 1.27)
		(stroke
			(width 0)
			(type default)
		)
	)
	(bus_entry
		(at 255.27 271.78)
		(size -1.27 1.27)
		(stroke
			(width 0)
			(type default)
		)
	)
	(bus_entry
		(at 382.27 196.85)
		(size -1.27 1.27)
		(stroke
			(width 0)
			(type default)
		)
	)
	(bus_entry
		(at 255.27 256.54)
		(size -1.27 1.27)
		(stroke
			(width 0)
			(type default)
		)
	)
	(bus_entry
		(at 384.81 31.75)
		(size -1.27 1.27)
		(stroke
			(width 0)
			(type default)
		)
	)
	(bus_entry
		(at 335.28 199.39)
		(size 1.27 1.27)
		(stroke
			(width 0)
			(type default)
		)
	)
	(bus_entry
		(at 265.43 234.95)
		(size 1.27 1.27)
		(stroke
			(width 0)
			(type default)
		)
	)
	(bus_entry
		(at 255.27 256.54)
		(size 1.27 1.27)
		(stroke
			(width 0)
			(type default)
		)
	)
	(bus_entry
		(at 293.37 204.47)
		(size -1.27 1.27)
		(stroke
			(width 0)
			(type default)
		)
	)
	(bus_entry
		(at 255.27 266.7)
		(size -1.27 1.27)
		(stroke
			(width 0)
			(type default)
		)
	)
	(bus_entry
		(at 293.37 194.31)
		(size -1.27 1.27)
		(stroke
			(width 0)
			(type default)
		)
	)
	(bus_entry
		(at 35.56 273.05)
		(size 1.27 0)
		(stroke
			(width 0)
			(type default)
		)
	)
	(bus_entry
		(at 43.18 200.66)
		(size 1.27 1.27)
		(stroke
			(width 0)
			(type default)
		)
	)
	(bus_entry
		(at 293.37 171.45)
		(size -1.27 1.27)
		(stroke
			(width 0)
			(type default)
		)
	)
	(bus_entry
		(at 382.27 171.45)
		(size -1.27 1.27)
		(stroke
			(width 0)
			(type default)
		)
	)
	(bus_entry
		(at 382.27 163.83)
		(size -1.27 1.27)
		(stroke
			(width 0)
			(type default)
		)
	)
	(bus_entry
		(at 246.38 166.37)
		(size 1.27 1.27)
		(stroke
			(width 0)
			(type default)
		)
	)
	(bus_entry
		(at 335.28 184.15)
		(size 1.27 1.27)
		(stroke
			(width 0)
			(type default)
		)
	)
	(bus_entry
		(at 311.15 229.87)
		(size 1.27 1.27)
		(stroke
			(width 0)
			(type default)
		)
	)
	(bus_entry
		(at 382.27 179.07)
		(size -1.27 1.27)
		(stroke
			(width 0)
			(type default)
		)
	)
	(bus_entry
		(at 125.73 181.61)
		(size 1.27 1.27)
		(stroke
			(width 0)
			(type default)
		)
	)
	(bus_entry
		(at 255.27 274.32)
		(size 1.27 1.27)
		(stroke
			(width 0)
			(type default)
		)
	)
	(bus_entry
		(at 335.28 171.45)
		(size 1.27 1.27)
		(stroke
			(width 0)
			(type default)
		)
	)
	(bus_entry
		(at 255.27 266.7)
		(size 1.27 1.27)
		(stroke
			(width 0)
			(type default)
		)
	)
	(bus_entry
		(at 384.81 34.29)
		(size -1.27 1.27)
		(stroke
			(width 0)
			(type default)
		)
	)
	(bus_entry
		(at 246.38 184.15)
		(size 1.27 1.27)
		(stroke
			(width 0)
			(type default)
		)
	)
	(bus_entry
		(at 293.37 186.69)
		(size -1.27 1.27)
		(stroke
			(width 0)
			(type default)
		)
	)
	(bus_entry
		(at 166.37 93.98)
		(size -1.27 1.27)
		(stroke
			(width 0)
			(type default)
		)
	)
	(bus_entry
		(at 293.37 179.07)
		(size -1.27 1.27)
		(stroke
			(width 0)
			(type default)
		)
	)
	(bus_entry
		(at 382.27 191.77)
		(size -1.27 1.27)
		(stroke
			(width 0)
			(type default)
		)
	)
	(bus_entry
		(at 246.38 168.91)
		(size 1.27 1.27)
		(stroke
			(width 0)
			(type default)
		)
	)
	(bus_entry
		(at 293.37 173.99)
		(size -1.27 1.27)
		(stroke
			(width 0)
			(type default)
		)
	)
	(bus_entry
		(at 265.43 229.87)
		(size 1.27 1.27)
		(stroke
			(width 0)
			(type default)
		)
	)
	(bus_entry
		(at 293.37 191.77)
		(size -1.27 1.27)
		(stroke
			(width 0)
			(type default)
		)
	)
	(bus_entry
		(at 245.11 36.83)
		(size 1.27 1.27)
		(stroke
			(width 0)
			(type default)
		)
	)
	(bus_entry
		(at 384.81 41.91)
		(size -1.27 1.27)
		(stroke
			(width 0)
			(type default)
		)
	)
	(bus_entry
		(at 43.18 218.44)
		(size 1.27 1.27)
		(stroke
			(width 0)
			(type default)
		)
	)
	(bus_entry
		(at 58.42 91.44)
		(size 1.27 1.27)
		(stroke
			(width 0)
			(type default)
		)
	)
	(bus_entry
		(at 334.01 90.17)
		(size 1.27 1.27)
		(stroke
			(width 0)
			(type default)
		)
	)
	(bus_entry
		(at 246.38 189.23)
		(size 1.27 1.27)
		(stroke
			(width 0)
			(type default)
		)
	)
	(bus_entry
		(at 382.27 194.31)
		(size -1.27 1.27)
		(stroke
			(width 0)
			(type default)
		)
	)
	(bus_entry
		(at 43.18 181.61)
		(size 1.27 1.27)
		(stroke
			(width 0)
			(type default)
		)
	)
	(bus_entry
		(at 245.11 46.99)
		(size 1.27 1.27)
		(stroke
			(width 0)
			(type default)
		)
	)
	(bus_entry
		(at 335.28 166.37)
		(size 1.27 1.27)
		(stroke
			(width 0)
			(type default)
		)
	)
	(bus_entry
		(at 255.27 269.24)
		(size -1.27 1.27)
		(stroke
			(width 0)
			(type default)
		)
	)
	(bus_entry
		(at 259.08 109.22)
		(size 1.27 1.27)
		(stroke
			(width 0)
			(type default)
		)
	)
	(bus_entry
		(at 335.28 163.83)
		(size 1.27 1.27)
		(stroke
			(width 0)
			(type default)
		)
	)
	(bus_entry
		(at 255.27 261.62)
		(size 1.27 1.27)
		(stroke
			(width 0)
			(type default)
		)
	)
	(bus_entry
		(at 246.38 196.85)
		(size 1.27 1.27)
		(stroke
			(width 0)
			(type default)
		)
	)
	(bus_entry
		(at 384.81 39.37)
		(size -1.27 1.27)
		(stroke
			(width 0)
			(type default)
		)
	)
	(bus_entry
		(at 335.28 168.91)
		(size 1.27 1.27)
		(stroke
			(width 0)
			(type default)
		)
	)
	(bus_entry
		(at 259.08 90.17)
		(size 1.27 1.27)
		(stroke
			(width 0)
			(type default)
		)
	)
	(bus_entry
		(at 384.81 46.99)
		(size -1.27 1.27)
		(stroke
			(width 0)
			(type default)
		)
	)
	(bus_entry
		(at 335.28 194.31)
		(size 1.27 1.27)
		(stroke
			(width 0)
			(type default)
		)
	)
	(bus_entry
		(at 165.1 34.29)
		(size -1.27 1.27)
		(stroke
			(width 0)
			(type default)
		)
	)
	(bus_entry
		(at 245.11 44.45)
		(size 1.27 1.27)
		(stroke
			(width 0)
			(type default)
		)
	)
	(bus_entry
		(at 382.27 166.37)
		(size -1.27 1.27)
		(stroke
			(width 0)
			(type default)
		)
	)
	(bus_entry
		(at 58.42 88.9)
		(size 1.27 1.27)
		(stroke
			(width 0)
			(type default)
		)
	)
	(bus_entry
		(at 335.28 176.53)
		(size 1.27 1.27)
		(stroke
			(width 0)
			(type default)
		)
	)
	(bus_entry
		(at 43.18 162.56)
		(size 1.27 1.27)
		(stroke
			(width 0)
			(type default)
		)
	)
	(bus_entry
		(at 382.27 173.99)
		(size -1.27 1.27)
		(stroke
			(width 0)
			(type default)
		)
	)
	(bus_entry
		(at 58.42 93.98)
		(size 1.27 1.27)
		(stroke
			(width 0)
			(type default)
		)
	)
	(wire
		(pts
			(xy 247.65 175.26) (xy 264.16 175.26)
		)
		(stroke
			(width 0)
			(type default)
		)
	)
	(bus
		(pts
			(xy 57.15 31.75) (xy 57.15 29.21)
		)
		(stroke
			(width 0)
			(type default)
		)
	)
	(wire
		(pts
			(xy 276.86 160.02) (xy 274.32 160.02)
		)
		(stroke
			(width 0)
			(type default)
		)
	)
	(bus
		(pts
			(xy 43.18 181.61) (xy 43.18 200.66)
		)
		(stroke
			(width 0)
			(type default)
		)
	)
	(wire
		(pts
			(xy 365.76 182.88) (xy 365.76 200.66)
		)
		(stroke
			(width 0)
			(type default)
		)
	)
	(wire
		(pts
			(xy 177.8 252.73) (xy 180.34 252.73)
		)
		(stroke
			(width 0)
			(type default)
		)
	)
	(wire
		(pts
			(xy 101.6 40.64) (xy 101.6 43.18)
		)
		(stroke
			(width 0)
			(type default)
		)
	)
	(wire
		(pts
			(xy 127 163.83) (xy 179.07 163.83)
		)
		(stroke
			(width 0)
			(type default)
		)
	)
	(wire
		(pts
			(xy 223.52 273.05) (xy 223.52 275.59)
		)
		(stroke
			(width 0)
			(type default)
		)
	)
	(bus
		(pts
			(xy 259.08 90.17) (xy 259.08 109.22)
		)
		(stroke
			(width 0)
			(type default)
		)
	)
	(wire
		(pts
			(xy 246.38 40.64) (xy 274.32 40.64)
		)
		(stroke
			(width 0)
			(type default)
		)
	)
	(wire
		(pts
			(xy 307.34 50.8) (xy 306.07 50.8)
		)
		(stroke
			(width 0)
			(type default)
		)
	)
	(wire
		(pts
			(xy 279.4 43.18) (xy 307.34 43.18)
		)
		(stroke
			(width 0)
			(type default)
		)
	)
	(wire
		(pts
			(xy 186.69 193.04) (xy 186.69 194.31)
		)
		(stroke
			(width 0)
			(type default)
		)
	)
	(wire
		(pts
			(xy 274.32 182.88) (xy 276.86 182.88)
		)
		(stroke
			(width 0)
			(type default)
		)
	)
	(wire
		(pts
			(xy 247.65 170.18) (xy 264.16 170.18)
		)
		(stroke
			(width 0)
			(type default)
		)
	)
	(wire
		(pts
			(xy 326.39 31.75) (xy 326.39 38.1)
		)
		(stroke
			(width 0)
			(type default)
		)
	)
	(wire
		(pts
			(xy 68.58 273.05) (xy 68.58 280.67)
		)
		(stroke
			(width 0)
			(type default)
		)
	)
	(bus
		(pts
			(xy 293.37 173.99) (xy 293.37 176.53)
		)
		(stroke
			(width 0)
			(type default)
		)
	)
	(wire
		(pts
			(xy 299.72 113.03) (xy 306.07 113.03)
		)
		(stroke
			(width 0)
			(type default)
		)
	)
	(wire
		(pts
			(xy 68.58 280.67) (xy 116.84 280.67)
		)
		(stroke
			(width 0)
			(type default)
		)
	)
	(wire
		(pts
			(xy 274.32 200.66) (xy 276.86 200.66)
		)
		(stroke
			(width 0)
			(type default)
		)
	)
	(wire
		(pts
			(xy 292.1 232.41) (xy 311.15 232.41)
		)
		(stroke
			(width 0)
			(type default)
		)
	)
	(wire
		(pts
			(xy 140.97 90.17) (xy 165.1 90.17)
		)
		(stroke
			(width 0)
			(type default)
		)
	)
	(bus
		(pts
			(xy 332.74 74.93) (xy 334.01 76.2)
		)
		(stroke
			(width 0)
			(type default)
		)
	)
	(polyline
		(pts
			(xy 203.2 13.97) (xy 203.2 127)
		)
		(stroke
			(width 0)
			(type default)
		)
	)
	(wire
		(pts
			(xy 76.2 242.57) (xy 76.2 245.11)
		)
		(stroke
			(width 0)
			(type default)
		)
	)
	(wire
		(pts
			(xy 292.1 265.43) (xy 295.91 265.43)
		)
		(stroke
			(width 0)
			(type default)
		)
	)
	(wire
		(pts
			(xy 116.84 35.56) (xy 135.89 35.56)
		)
		(stroke
			(width 0)
			(type default)
		)
	)
	(bus
		(pts
			(xy 245.11 36.83) (xy 245.11 34.29)
		)
		(stroke
			(width 0)
			(type default)
		)
	)
	(bus
		(pts
			(xy 266.7 233.68) (xy 266.7 236.22)
		)
		(stroke
			(width 0)
			(type default)
		)
	)
	(wire
		(pts
			(xy 295.91 257.81) (xy 295.91 260.35)
		)
		(stroke
			(width 0)
			(type default)
		)
	)
	(wire
		(pts
			(xy 44.45 201.93) (xy 96.52 201.93)
		)
		(stroke
			(width 0)
			(type default)
		)
	)
	(wire
		(pts
			(xy 279.4 45.72) (xy 307.34 45.72)
		)
		(stroke
			(width 0)
			(type default)
		)
	)
	(wire
		(pts
			(xy 76.2 212.09) (xy 87.63 212.09)
		)
		(stroke
			(width 0)
			(type default)
		)
	)
	(bus
		(pts
			(xy 293.37 179.07) (xy 293.37 186.69)
		)
		(stroke
			(width 0)
			(type default)
		)
	)
	(bus
		(pts
			(xy 293.37 176.53) (xy 293.37 179.07)
		)
		(stroke
			(width 0)
			(type default)
		)
	)
	(wire
		(pts
			(xy 120.65 97.79) (xy 120.65 100.33)
		)
		(stroke
			(width 0)
			(type default)
		)
	)
	(wire
		(pts
			(xy 87.63 95.25) (xy 106.68 95.25)
		)
		(stroke
			(width 0)
			(type default)
		)
	)
	(wire
		(pts
			(xy 292.1 278.13) (xy 295.91 278.13)
		)
		(stroke
			(width 0)
			(type default)
		)
	)
	(wire
		(pts
			(xy 354.33 110.49) (xy 361.95 110.49)
		)
		(stroke
			(width 0)
			(type default)
		)
	)
	(wire
		(pts
			(xy 59.69 87.63) (xy 82.55 87.63)
		)
		(stroke
			(width 0)
			(type default)
		)
	)
	(wire
		(pts
			(xy 292.1 234.95) (xy 311.15 234.95)
		)
		(stroke
			(width 0)
			(type default)
		)
	)
	(wire
		(pts
			(xy 105.41 52.07) (xy 111.76 52.07)
		)
		(stroke
			(width 0)
			(type default)
		)
	)
	(wire
		(pts
			(xy 198.12 165.1) (xy 198.12 163.83)
		)
		(stroke
			(width 0)
			(type default)
		)
	)
	(wire
		(pts
			(xy 101.6 97.79) (xy 101.6 100.33)
		)
		(stroke
			(width 0)
			(type default)
		)
	)
	(wire
		(pts
			(xy 111.76 116.84) (xy 111.76 119.38)
		)
		(stroke
			(width 0)
			(type default)
		)
	)
	(bus
		(pts
			(xy 335.28 149.86) (xy 335.28 158.75)
		)
		(stroke
			(width 0)
			(type default)
		)
	)
	(bus
		(pts
			(xy 335.28 166.37) (xy 335.28 168.91)
		)
		(stroke
			(width 0)
			(type default)
		)
	)
	(wire
		(pts
			(xy 336.55 172.72) (xy 353.06 172.72)
		)
		(stroke
			(width 0)
			(type default)
		)
	)
	(wire
		(pts
			(xy 224.79 275.59) (xy 223.52 275.59)
		)
		(stroke
			(width 0)
			(type default)
		)
	)
	(polyline
		(pts
			(xy 209.55 13.97) (xy 209.55 63.5)
		)
		(stroke
			(width 0)
			(type default)
		)
	)
	(wire
		(pts
			(xy 54.61 173.99) (xy 49.53 173.99)
		)
		(stroke
			(width 0)
			(type default)
		)
	)
	(wire
		(pts
			(xy 54.61 193.04) (xy 49.53 193.04)
		)
		(stroke
			(width 0)
			(type default)
		)
	)
	(wire
		(pts
			(xy 317.5 43.18) (xy 351.79 43.18)
		)
		(stroke
			(width 0)
			(type default)
		)
	)
	(wire
		(pts
			(xy 274.32 185.42) (xy 281.94 185.42)
		)
		(stroke
			(width 0)
			(type default)
		)
	)
	(wire
		(pts
			(xy 381 193.04) (xy 363.22 193.04)
		)
		(stroke
			(width 0)
			(type default)
		)
	)
	(wire
		(pts
			(xy 246.38 232.41) (xy 265.43 232.41)
		)
		(stroke
			(width 0)
			(type default)
		)
	)
	(wire
		(pts
			(xy 247.65 200.66) (xy 264.16 200.66)
		)
		(stroke
			(width 0)
			(type default)
		)
	)
	(bus
		(pts
			(xy 266.7 238.76) (xy 266.7 243.84)
		)
		(stroke
			(width 0)
			(type default)
		)
	)
	(bus
		(pts
			(xy 293.37 201.93) (xy 293.37 204.47)
		)
		(stroke
			(width 0)
			(type default)
		)
	)
	(wire
		(pts
			(xy 363.22 170.18) (xy 381 170.18)
		)
		(stroke
			(width 0)
			(type default)
		)
	)
	(wire
		(pts
			(xy 116.84 87.63) (xy 135.89 87.63)
		)
		(stroke
			(width 0)
			(type default)
		)
	)
	(wire
		(pts
			(xy 292.1 273.05) (xy 295.91 273.05)
		)
		(stroke
			(width 0)
			(type default)
		)
	)
	(wire
		(pts
			(xy 276.86 167.64) (xy 274.32 167.64)
		)
		(stroke
			(width 0)
			(type default)
		)
	)
	(polyline
		(pts
			(xy 209.55 284.48) (xy 209.55 219.71)
		)
		(stroke
			(width 0)
			(type default)
		)
	)
	(wire
		(pts
			(xy 118.11 100.33) (xy 116.84 100.33)
		)
		(stroke
			(width 0)
			(type default)
		)
	)
	(wire
		(pts
			(xy 96.52 181.61) (xy 96.52 182.88)
		)
		(stroke
			(width 0)
			(type default)
		)
	)
	(wire
		(pts
			(xy 292.1 270.51) (xy 295.91 270.51)
		)
		(stroke
			(width 0)
			(type default)
		)
	)
	(bus
		(pts
			(xy 53.34 83.82) (xy 58.42 83.82)
		)
		(stroke
			(width 0)
			(type default)
		)
	)
	(wire
		(pts
			(xy 198.12 184.15) (xy 198.12 182.88)
		)
		(stroke
			(width 0)
			(type default)
		)
	)
	(bus
		(pts
			(xy 43.18 200.66) (xy 43.18 218.44)
		)
		(stroke
			(width 0)
			(type default)
		)
	)
	(wire
		(pts
			(xy 292.1 240.03) (xy 308.61 240.03)
		)
		(stroke
			(width 0)
			(type default)
		)
	)
	(bus
		(pts
			(xy 165.1 31.75) (xy 165.1 34.29)
		)
		(stroke
			(width 0)
			(type default)
		)
	)
	(wire
		(pts
			(xy 287.02 113.03) (xy 289.56 113.03)
		)
		(stroke
			(width 0)
			(type default)
		)
	)
	(wire
		(pts
			(xy 224.79 273.05) (xy 223.52 273.05)
		)
		(stroke
			(width 0)
			(type default)
		)
	)
	(wire
		(pts
			(xy 180.34 250.19) (xy 179.07 250.19)
		)
		(stroke
			(width 0)
			(type default)
		)
	)
	(wire
		(pts
			(xy 139.7 250.19) (xy 138.43 250.19)
		)
		(stroke
			(width 0)
			(type default)
		)
	)
	(bus
		(pts
			(xy 245.11 41.91) (xy 245.11 39.37)
		)
		(stroke
			(width 0)
			(type default)
		)
	)
	(wire
		(pts
			(xy 104.14 193.04) (xy 104.14 194.31)
		)
		(stroke
			(width 0)
			(type default)
		)
	)
	(wire
		(pts
			(xy 142.24 212.09) (xy 153.67 212.09)
		)
		(stroke
			(width 0)
			(type default)
		)
	)
	(wire
		(pts
			(xy 224.79 267.97) (xy 223.52 267.97)
		)
		(stroke
			(width 0)
			(type default)
		)
	)
	(wire
		(pts
			(xy 381 195.58) (xy 363.22 195.58)
		)
		(stroke
			(width 0)
			(type default)
		)
	)
	(wire
		(pts
			(xy 165.1 257.81) (xy 180.34 257.81)
		)
		(stroke
			(width 0)
			(type default)
		)
	)
	(wire
		(pts
			(xy 86.36 250.19) (xy 86.36 251.46)
		)
		(stroke
			(width 0)
			(type default)
		)
	)
	(wire
		(pts
			(xy 72.39 267.97) (xy 105.41 267.97)
		)
		(stroke
			(width 0)
			(type default)
		)
	)
	(wire
		(pts
			(xy 276.86 165.1) (xy 276.86 162.56)
		)
		(stroke
			(width 0)
			(type default)
		)
	)
	(wire
		(pts
			(xy 127 219.71) (xy 179.07 219.71)
		)
		(stroke
			(width 0)
			(type default)
		)
	)
	(wire
		(pts
			(xy 104.14 154.94) (xy 104.14 156.21)
		)
		(stroke
			(width 0)
			(type default)
		)
	)
	(wire
		(pts
			(xy 363.22 182.88) (xy 365.76 182.88)
		)
		(stroke
			(width 0)
			(type default)
		)
	)
	(wire
		(pts
			(xy 58.42 30.48) (xy 82.55 30.48)
		)
		(stroke
			(width 0)
			(type default)
		)
	)
	(wire
		(pts
			(xy 295.91 260.35) (xy 295.91 262.89)
		)
		(stroke
			(width 0)
			(type default)
		)
	)
	(wire
		(pts
			(xy 224.79 260.35) (xy 223.52 260.35)
		)
		(stroke
			(width 0)
			(type default)
		)
	)
	(wire
		(pts
			(xy 336.55 160.02) (xy 353.06 160.02)
		)
		(stroke
			(width 0)
			(type default)
		)
	)
	(wire
		(pts
			(xy 377.19 88.9) (xy 377.19 91.44)
		)
		(stroke
			(width 0)
			(type default)
		)
	)
	(bus
		(pts
			(xy 166.37 85.09) (xy 166.37 86.36)
		)
		(stroke
			(width 0)
			(type default)
		)
	)
	(wire
		(pts
			(xy 49.53 207.01) (xy 49.53 212.09)
		)
		(stroke
			(width 0)
			(type default)
		)
	)
	(wire
		(pts
			(xy 317.5 38.1) (xy 326.39 38.1)
		)
		(stroke
			(width 0)
			(type default)
		)
	)
	(wire
		(pts
			(xy 111.76 109.22) (xy 111.76 111.76)
		)
		(stroke
			(width 0)
			(type default)
		)
	)
	(wire
		(pts
			(xy 137.16 173.99) (xy 132.08 173.99)
		)
		(stroke
			(width 0)
			(type default)
		)
	)
	(wire
		(pts
			(xy 356.87 33.02) (xy 383.54 33.02)
		)
		(stroke
			(width 0)
			(type default)
		)
	)
	(wire
		(pts
			(xy 115.57 163.83) (xy 113.03 163.83)
		)
		(stroke
			(width 0)
			(type default)
		)
	)
	(bus
		(pts
			(xy 34.29 273.05) (xy 35.56 273.05)
		)
		(stroke
			(width 0)
			(type default)
		)
	)
	(wire
		(pts
			(xy 76.2 173.99) (xy 87.63 173.99)
		)
		(stroke
			(width 0)
			(type default)
		)
	)
	(bus
		(pts
			(xy 313.69 248.92) (xy 316.23 248.92)
		)
		(stroke
			(width 0)
			(type default)
		)
	)
	(bus
		(pts
			(xy 266.7 243.84) (xy 267.97 245.11)
		)
		(stroke
			(width 0)
			(type default)
		)
	)
	(polyline
		(pts
			(xy 406.4 219.71) (xy 209.55 219.71)
		)
		(stroke
			(width 0)
			(type default)
		)
	)
	(bus
		(pts
			(xy 323.85 149.86) (xy 335.28 149.86)
		)
		(stroke
			(width 0)
			(type default)
		)
	)
	(bus
		(pts
			(xy 125.73 181.61) (xy 125.73 200.66)
		)
		(stroke
			(width 0)
			(type default)
		)
	)
	(polyline
		(pts
			(xy 406.4 69.85) (xy 209.55 69.85)
		)
		(stroke
			(width 0)
			(type default)
		)
	)
	(wire
		(pts
			(xy 279.4 107.95) (xy 279.4 110.49)
		)
		(stroke
			(width 0)
			(type default)
		)
	)
	(bus
		(pts
			(xy 382.27 173.99) (xy 382.27 176.53)
		)
		(stroke
			(width 0)
			(type default)
		)
	)
	(wire
		(pts
			(xy 365.76 160.02) (xy 363.22 160.02)
		)
		(stroke
			(width 0)
			(type default)
		)
	)
	(bus
		(pts
			(xy 382.27 163.83) (xy 382.27 166.37)
		)
		(stroke
			(width 0)
			(type default)
		)
	)
	(wire
		(pts
			(xy 116.84 92.71) (xy 135.89 92.71)
		)
		(stroke
			(width 0)
			(type default)
		)
	)
	(wire
		(pts
			(xy 100.33 212.09) (xy 104.14 212.09)
		)
		(stroke
			(width 0)
			(type default)
		)
	)
	(wire
		(pts
			(xy 292.1 172.72) (xy 274.32 172.72)
		)
		(stroke
			(width 0)
			(type default)
		)
	)
	(wire
		(pts
			(xy 223.52 267.97) (xy 223.52 270.51)
		)
		(stroke
			(width 0)
			(type default)
		)
	)
	(wire
		(pts
			(xy 317.5 30.48) (xy 318.77 30.48)
		)
		(stroke
			(width 0)
			(type default)
		)
	)
	(wire
		(pts
			(xy 116.84 90.17) (xy 135.89 90.17)
		)
		(stroke
			(width 0)
			(type default)
		)
	)
	(bus
		(pts
			(xy 57.15 34.29) (xy 57.15 31.75)
		)
		(stroke
			(width 0)
			(type default)
		)
	)
	(bus
		(pts
			(xy 246.38 184.15) (xy 246.38 186.69)
		)
		(stroke
			(width 0)
			(type default)
		)
	)
	(wire
		(pts
			(xy 44.45 163.83) (xy 96.52 163.83)
		)
		(stroke
			(width 0)
			(type default)
		)
	)
	(wire
		(pts
			(xy 224.79 270.51) (xy 223.52 270.51)
		)
		(stroke
			(width 0)
			(type default)
		)
	)
	(bus
		(pts
			(xy 382.27 186.69) (xy 382.27 189.23)
		)
		(stroke
			(width 0)
			(type default)
		)
	)
	(wire
		(pts
			(xy 247.65 193.04) (xy 264.16 193.04)
		)
		(stroke
			(width 0)
			(type default)
		)
	)
	(bus
		(pts
			(xy 124.46 142.24) (xy 125.73 143.51)
		)
		(stroke
			(width 0)
			(type default)
		)
	)
	(wire
		(pts
			(xy 179.07 219.71) (xy 190.5 219.71)
		)
		(stroke
			(width 0)
			(type default)
		)
	)
	(wire
		(pts
			(xy 279.4 40.64) (xy 307.34 40.64)
		)
		(stroke
			(width 0)
			(type default)
		)
	)
	(wire
		(pts
			(xy 279.4 110.49) (xy 287.02 110.49)
		)
		(stroke
			(width 0)
			(type default)
		)
	)
	(wire
		(pts
			(xy 138.43 260.35) (xy 138.43 261.62)
		)
		(stroke
			(width 0)
			(type default)
		)
	)
	(wire
		(pts
			(xy 224.79 257.81) (xy 223.52 257.81)
		)
		(stroke
			(width 0)
			(type default)
		)
	)
	(wire
		(pts
			(xy 306.07 50.8) (xy 306.07 53.34)
		)
		(stroke
			(width 0)
			(type default)
		)
	)
	(bus
		(pts
			(xy 246.38 196.85) (xy 246.38 199.39)
		)
		(stroke
			(width 0)
			(type default)
		)
	)
	(wire
		(pts
			(xy 309.88 93.98) (xy 312.42 93.98)
		)
		(stroke
			(width 0)
			(type default)
		)
	)
	(wire
		(pts
			(xy 198.12 203.2) (xy 198.12 201.93)
		)
		(stroke
			(width 0)
			(type default)
		)
	)
	(wire
		(pts
			(xy 276.86 170.18) (xy 274.32 170.18)
		)
		(stroke
			(width 0)
			(type default)
		)
	)
	(wire
		(pts
			(xy 106.68 40.64) (xy 101.6 40.64)
		)
		(stroke
			(width 0)
			(type default)
		)
	)
	(wire
		(pts
			(xy 381 180.34) (xy 363.22 180.34)
		)
		(stroke
			(width 0)
			(type default)
		)
	)
	(wire
		(pts
			(xy 256.54 265.43) (xy 279.4 265.43)
		)
		(stroke
			(width 0)
			(type default)
		)
	)
	(bus
		(pts
			(xy 293.37 186.69) (xy 293.37 189.23)
		)
		(stroke
			(width 0)
			(type default)
		)
	)
	(wire
		(pts
			(xy 96.52 182.88) (xy 107.95 182.88)
		)
		(stroke
			(width 0)
			(type default)
		)
	)
	(wire
		(pts
			(xy 123.19 271.78) (xy 123.19 274.32)
		)
		(stroke
			(width 0)
			(type default)
		)
	)
	(wire
		(pts
			(xy 336.55 187.96) (xy 353.06 187.96)
		)
		(stroke
			(width 0)
			(type default)
		)
	)
	(bus
		(pts
			(xy 165.1 34.29) (xy 165.1 36.83)
		)
		(stroke
			(width 0)
			(type default)
		)
	)
	(wire
		(pts
			(xy 356.87 45.72) (xy 383.54 45.72)
		)
		(stroke
			(width 0)
			(type default)
		)
	)
	(wire
		(pts
			(xy 317.5 45.72) (xy 351.79 45.72)
		)
		(stroke
			(width 0)
			(type default)
		)
	)
	(wire
		(pts
			(xy 158.75 193.04) (xy 170.18 193.04)
		)
		(stroke
			(width 0)
			(type default)
		)
	)
	(bus
		(pts
			(xy 246.38 186.69) (xy 246.38 189.23)
		)
		(stroke
			(width 0)
			(type default)
		)
	)
	(wire
		(pts
			(xy 124.46 267.97) (xy 165.1 267.97)
		)
		(stroke
			(width 0)
			(type default)
		)
	)
	(bus
		(pts
			(xy 255.27 271.78) (xy 255.27 274.32)
		)
		(stroke
			(width 0)
			(type default)
		)
	)
	(wire
		(pts
			(xy 361.95 113.03) (xy 364.49 113.03)
		)
		(stroke
			(width 0)
			(type default)
		)
	)
	(wire
		(pts
			(xy 363.22 185.42) (xy 370.84 185.42)
		)
		(stroke
			(width 0)
			(type default)
		)
	)
	(wire
		(pts
			(xy 279.4 38.1) (xy 307.34 38.1)
		)
		(stroke
			(width 0)
			(type default)
		)
	)
	(wire
		(pts
			(xy 256.54 267.97) (xy 279.4 267.97)
		)
		(stroke
			(width 0)
			(type default)
		)
	)
	(wire
		(pts
			(xy 309.88 91.44) (xy 309.88 93.98)
		)
		(stroke
			(width 0)
			(type default)
		)
	)
	(wire
		(pts
			(xy 129.54 250.19) (xy 129.54 251.46)
		)
		(stroke
			(width 0)
			(type default)
		)
	)
	(polyline
		(pts
			(xy 406.4 217.17) (xy 209.55 217.17)
		)
		(stroke
			(width 0)
			(type default)
		)
	)
	(wire
		(pts
			(xy 100.33 193.04) (xy 104.14 193.04)
		)
		(stroke
			(width 0)
			(type default)
		)
	)
	(wire
		(pts
			(xy 279.4 119.38) (xy 279.4 121.92)
		)
		(stroke
			(width 0)
			(type default)
		)
	)
	(wire
		(pts
			(xy 247.65 203.2) (xy 264.16 203.2)
		)
		(stroke
			(width 0)
			(type default)
		)
	)
	(wire
		(pts
			(xy 54.61 154.94) (xy 49.53 154.94)
		)
		(stroke
			(width 0)
			(type default)
		)
	)
	(wire
		(pts
			(xy 234.95 262.89) (xy 254 262.89)
		)
		(stroke
			(width 0)
			(type default)
		)
	)
	(bus
		(pts
			(xy 267.97 245.11) (xy 270.51 245.11)
		)
		(stroke
			(width 0)
			(type default)
		)
	)
	(wire
		(pts
			(xy 381 187.96) (xy 363.22 187.96)
		)
		(stroke
			(width 0)
			(type default)
		)
	)
	(wire
		(pts
			(xy 106.68 100.33) (xy 105.41 100.33)
		)
		(stroke
			(width 0)
			(type default)
		)
	)
	(wire
		(pts
			(xy 59.69 173.99) (xy 71.12 173.99)
		)
		(stroke
			(width 0)
			(type default)
		)
	)
	(bus
		(pts
			(xy 255.27 266.7) (xy 255.27 264.16)
		)
		(stroke
			(width 0)
			(type default)
		)
	)
	(polyline
		(pts
			(xy 203.2 234.95) (xy 13.97 234.95)
		)
		(stroke
			(width 0)
			(type default)
		)
	)
	(wire
		(pts
			(xy 68.58 261.62) (xy 68.58 262.89)
		)
		(stroke
			(width 0)
			(type default)
		)
	)
	(bus
		(pts
			(xy 246.38 166.37) (xy 246.38 168.91)
		)
		(stroke
			(width 0)
			(type default)
		)
	)
	(wire
		(pts
			(xy 292.1 195.58) (xy 274.32 195.58)
		)
		(stroke
			(width 0)
			(type default)
		)
	)
	(wire
		(pts
			(xy 111.76 59.69) (xy 111.76 62.23)
		)
		(stroke
			(width 0)
			(type default)
		)
	)
	(wire
		(pts
			(xy 115.57 184.15) (xy 115.57 182.88)
		)
		(stroke
			(width 0)
			(type default)
		)
	)
	(wire
		(pts
			(xy 100.33 154.94) (xy 104.14 154.94)
		)
		(stroke
			(width 0)
			(type default)
		)
	)
	(bus
		(pts
			(xy 335.28 149.86) (xy 381 149.86)
		)
		(stroke
			(width 0)
			(type default)
		)
	)
	(wire
		(pts
			(xy 87.63 87.63) (xy 106.68 87.63)
		)
		(stroke
			(width 0)
			(type default)
		)
	)
	(wire
		(pts
			(xy 365.76 200.66) (xy 365.76 201.93)
		)
		(stroke
			(width 0)
			(type default)
		)
	)
	(bus
		(pts
			(xy 384.81 34.29) (xy 384.81 39.37)
		)
		(stroke
			(width 0)
			(type default)
		)
	)
	(wire
		(pts
			(xy 58.42 33.02) (xy 82.55 33.02)
		)
		(stroke
			(width 0)
			(type default)
		)
	)
	(wire
		(pts
			(xy 317.5 48.26) (xy 351.79 48.26)
		)
		(stroke
			(width 0)
			(type default)
		)
	)
	(wire
		(pts
			(xy 105.41 267.97) (xy 124.46 267.97)
		)
		(stroke
			(width 0)
			(type default)
		)
	)
	(wire
		(pts
			(xy 96.52 162.56) (xy 96.52 163.83)
		)
		(stroke
			(width 0)
			(type default)
		)
	)
	(wire
		(pts
			(xy 182.88 193.04) (xy 186.69 193.04)
		)
		(stroke
			(width 0)
			(type default)
		)
	)
	(wire
		(pts
			(xy 158.75 173.99) (xy 170.18 173.99)
		)
		(stroke
			(width 0)
			(type default)
		)
	)
	(bus
		(pts
			(xy 246.38 189.23) (xy 246.38 191.77)
		)
		(stroke
			(width 0)
			(type default)
		)
	)
	(wire
		(pts
			(xy 247.65 205.74) (xy 264.16 205.74)
		)
		(stroke
			(width 0)
			(type default)
		)
	)
	(wire
		(pts
			(xy 323.85 175.26) (xy 353.06 175.26)
		)
		(stroke
			(width 0)
			(type default)
		)
	)
	(bus
		(pts
			(xy 255.27 269.24) (xy 255.27 266.7)
		)
		(stroke
			(width 0)
			(type default)
		)
	)
	(bus
		(pts
			(xy 335.28 184.15) (xy 335.28 186.69)
		)
		(stroke
			(width 0)
			(type default)
		)
	)
	(wire
		(pts
			(xy 295.91 267.97) (xy 295.91 270.51)
		)
		(stroke
			(width 0)
			(type default)
		)
	)
	(wire
		(pts
			(xy 179.07 162.56) (xy 179.07 163.83)
		)
		(stroke
			(width 0)
			(type default)
		)
	)
	(bus
		(pts
			(xy 335.28 189.23) (xy 335.28 191.77)
		)
		(stroke
			(width 0)
			(type default)
		)
	)
	(wire
		(pts
			(xy 116.84 280.67) (xy 116.84 279.4)
		)
		(stroke
			(width 0)
			(type default)
		)
	)
	(wire
		(pts
			(xy 179.07 181.61) (xy 179.07 182.88)
		)
		(stroke
			(width 0)
			(type default)
		)
	)
	(wire
		(pts
			(xy 292.1 237.49) (xy 311.15 237.49)
		)
		(stroke
			(width 0)
			(type default)
		)
	)
	(wire
		(pts
			(xy 247.65 198.12) (xy 264.16 198.12)
		)
		(stroke
			(width 0)
			(type default)
		)
	)
	(wire
		(pts
			(xy 364.49 110.49) (xy 361.95 110.49)
		)
		(stroke
			(width 0)
			(type default)
		)
	)
	(wire
		(pts
			(xy 97.79 257.81) (xy 76.2 257.81)
		)
		(stroke
			(width 0)
			(type default)
		)
	)
	(bus
		(pts
			(xy 293.37 171.45) (xy 293.37 173.99)
		)
		(stroke
			(width 0)
			(type default)
		)
	)
	(bus
		(pts
			(xy 246.38 149.86) (xy 246.38 158.75)
		)
		(stroke
			(width 0)
			(type default)
		)
	)
	(wire
		(pts
			(xy 292.1 229.87) (xy 311.15 229.87)
		)
		(stroke
			(width 0)
			(type default)
		)
	)
	(wire
		(pts
			(xy 36.83 273.05) (xy 57.15 273.05)
		)
		(stroke
			(width 0)
			(type default)
		)
	)
	(wire
		(pts
			(xy 247.65 187.96) (xy 264.16 187.96)
		)
		(stroke
			(width 0)
			(type default)
		)
	)
	(bus
		(pts
			(xy 246.38 176.53) (xy 246.38 179.07)
		)
		(stroke
			(width 0)
			(type default)
		)
	)
	(wire
		(pts
			(xy 223.52 255.27) (xy 223.52 257.81)
		)
		(stroke
			(width 0)
			(type default)
		)
	)
	(bus
		(pts
			(xy 246.38 204.47) (xy 246.38 207.01)
		)
		(stroke
			(width 0)
			(type default)
		)
	)
	(wire
		(pts
			(xy 127 201.93) (xy 179.07 201.93)
		)
		(stroke
			(width 0)
			(type default)
		)
	)
	(wire
		(pts
			(xy 140.97 33.02) (xy 163.83 33.02)
		)
		(stroke
			(width 0)
			(type default)
		)
	)
	(wire
		(pts
			(xy 318.77 30.48) (xy 318.77 54.61)
		)
		(stroke
			(width 0)
			(type default)
		)
	)
	(wire
		(pts
			(xy 262.89 241.3) (xy 262.89 240.03)
		)
		(stroke
			(width 0)
			(type default)
		)
	)
	(polyline
		(pts
			(xy 203.2 284.48) (xy 203.2 234.95)
		)
		(stroke
			(width 0)
			(type default)
		)
	)
	(bus
		(pts
			(xy 259.08 74.93) (xy 259.08 90.17)
		)
		(stroke
			(width 0)
			(type default)
		)
	)
	(wire
		(pts
			(xy 177.8 242.57) (xy 177.8 252.73)
		)
		(stroke
			(width 0)
			(type default)
		)
	)
	(wire
		(pts
			(xy 356.87 35.56) (xy 383.54 35.56)
		)
		(stroke
			(width 0)
			(type default)
		)
	)
	(wire
		(pts
			(xy 186.69 212.09) (xy 186.69 213.36)
		)
		(stroke
			(width 0)
			(type default)
		)
	)
	(wire
		(pts
			(xy 405.13 91.44) (xy 405.13 93.98)
		)
		(stroke
			(width 0)
			(type default)
		)
	)
	(wire
		(pts
			(xy 260.35 91.44) (xy 302.26 91.44)
		)
		(stroke
			(width 0)
			(type default)
		)
	)
	(bus
		(pts
			(xy 43.18 142.24) (xy 124.46 142.24)
		)
		(stroke
			(width 0)
			(type default)
		)
	)
	(wire
		(pts
			(xy 361.95 110.49) (xy 361.95 113.03)
		)
		(stroke
			(width 0)
			(type default)
		)
	)
	(bus
		(pts
			(xy 58.42 88.9) (xy 58.42 86.36)
		)
		(stroke
			(width 0)
			(type default)
		)
	)
	(wire
		(pts
			(xy 140.97 87.63) (xy 165.1 87.63)
		)
		(stroke
			(width 0)
			(type default)
		)
	)
	(wire
		(pts
			(xy 256.54 275.59) (xy 279.4 275.59)
		)
		(stroke
			(width 0)
			(type default)
		)
	)
	(wire
		(pts
			(xy 72.39 250.19) (xy 72.39 267.97)
		)
		(stroke
			(width 0)
			(type default)
		)
	)
	(bus
		(pts
			(xy 382.27 171.45) (xy 382.27 173.99)
		)
		(stroke
			(width 0)
			(type default)
		)
	)
	(wire
		(pts
			(xy 96.52 260.35) (xy 97.79 260.35)
		)
		(stroke
			(width 0)
			(type default)
		)
	)
	(wire
		(pts
			(xy 317.5 33.02) (xy 351.79 33.02)
		)
		(stroke
			(width 0)
			(type default)
		)
	)
	(wire
		(pts
			(xy 247.65 177.8) (xy 264.16 177.8)
		)
		(stroke
			(width 0)
			(type default)
		)
	)
	(wire
		(pts
			(xy 295.91 270.51) (xy 295.91 273.05)
		)
		(stroke
			(width 0)
			(type default)
		)
	)
	(wire
		(pts
			(xy 336.55 177.8) (xy 353.06 177.8)
		)
		(stroke
			(width 0)
			(type default)
		)
	)
	(wire
		(pts
			(xy 302.26 91.44) (xy 302.26 92.71)
		)
		(stroke
			(width 0)
			(type default)
		)
	)
	(polyline
		(pts
			(xy 209.55 69.85) (xy 209.55 127)
		)
		(stroke
			(width 0)
			(type default)
		)
	)
	(wire
		(pts
			(xy 354.33 110.49) (xy 354.33 114.3)
		)
		(stroke
			(width 0)
			(type default)
		)
	)
	(wire
		(pts
			(xy 118.11 52.07) (xy 118.11 43.18)
		)
		(stroke
			(width 0)
			(type default)
		)
	)
	(wire
		(pts
			(xy 247.65 190.5) (xy 264.16 190.5)
		)
		(stroke
			(width 0)
			(type default)
		)
	)
	(wire
		(pts
			(xy 137.16 193.04) (xy 132.08 193.04)
		)
		(stroke
			(width 0)
			(type default)
		)
	)
	(wire
		(pts
			(xy 96.52 260.35) (xy 96.52 261.62)
		)
		(stroke
			(width 0)
			(type default)
		)
	)
	(wire
		(pts
			(xy 279.4 35.56) (xy 307.34 35.56)
		)
		(stroke
			(width 0)
			(type default)
		)
	)
	(wire
		(pts
			(xy 363.22 165.1) (xy 381 165.1)
		)
		(stroke
			(width 0)
			(type default)
		)
	)
	(bus
		(pts
			(xy 293.37 151.13) (xy 293.37 171.45)
		)
		(stroke
			(width 0)
			(type default)
		)
	)
	(wire
		(pts
			(xy 62.23 280.67) (xy 68.58 280.67)
		)
		(stroke
			(width 0)
			(type default)
		)
	)
	(bus
		(pts
			(xy 165.1 27.94) (xy 163.83 26.67)
		)
		(stroke
			(width 0)
			(type default)
		)
	)
	(wire
		(pts
			(xy 246.38 237.49) (xy 265.43 237.49)
		)
		(stroke
			(width 0)
			(type default)
		)
	)
	(wire
		(pts
			(xy 336.55 167.64) (xy 353.06 167.64)
		)
		(stroke
			(width 0)
			(type default)
		)
	)
	(bus
		(pts
			(xy 335.28 158.75) (xy 335.28 161.29)
		)
		(stroke
			(width 0)
			(type default)
		)
	)
	(wire
		(pts
			(xy 137.16 242.57) (xy 137.16 252.73)
		)
		(stroke
			(width 0)
			(type default)
		)
	)
	(wire
		(pts
			(xy 111.76 50.8) (xy 111.76 52.07)
		)
		(stroke
			(width 0)
			(type default)
		)
	)
	(wire
		(pts
			(xy 59.69 193.04) (xy 71.12 193.04)
		)
		(stroke
			(width 0)
			(type default)
		)
	)
	(wire
		(pts
			(xy 129.54 245.11) (xy 129.54 242.57)
		)
		(stroke
			(width 0)
			(type default)
		)
	)
	(wire
		(pts
			(xy 142.24 193.04) (xy 153.67 193.04)
		)
		(stroke
			(width 0)
			(type default)
		)
	)
	(wire
		(pts
			(xy 292.1 262.89) (xy 295.91 262.89)
		)
		(stroke
			(width 0)
			(type default)
		)
	)
	(bus
		(pts
			(xy 57.15 36.83) (xy 57.15 34.29)
		)
		(stroke
			(width 0)
			(type default)
		)
	)
	(bus
		(pts
			(xy 165.1 83.82) (xy 58.42 83.82)
		)
		(stroke
			(width 0)
			(type default)
		)
	)
	(wire
		(pts
			(xy 116.84 97.79) (xy 120.65 97.79)
		)
		(stroke
			(width 0)
			(type default)
		)
	)
	(wire
		(pts
			(xy 336.55 180.34) (xy 353.06 180.34)
		)
		(stroke
			(width 0)
			(type default)
		)
	)
	(wire
		(pts
			(xy 246.38 45.72) (xy 274.32 45.72)
		)
		(stroke
			(width 0)
			(type default)
		)
	)
	(wire
		(pts
			(xy 234.95 275.59) (xy 254 275.59)
		)
		(stroke
			(width 0)
			(type default)
		)
	)
	(wire
		(pts
			(xy 76.2 154.94) (xy 87.63 154.94)
		)
		(stroke
			(width 0)
			(type default)
		)
	)
	(wire
		(pts
			(xy 170.18 250.19) (xy 170.18 251.46)
		)
		(stroke
			(width 0)
			(type default)
		)
	)
	(bus
		(pts
			(xy 292.1 149.86) (xy 293.37 151.13)
		)
		(stroke
			(width 0)
			(type default)
		)
	)
	(wire
		(pts
			(xy 179.07 163.83) (xy 190.5 163.83)
		)
		(stroke
			(width 0)
			(type default)
		)
	)
	(wire
		(pts
			(xy 306.07 113.03) (xy 306.07 115.57)
		)
		(stroke
			(width 0)
			(type default)
		)
	)
	(wire
		(pts
			(xy 292.1 257.81) (xy 295.91 257.81)
		)
		(stroke
			(width 0)
			(type default)
		)
	)
	(wire
		(pts
			(xy 186.69 154.94) (xy 186.69 156.21)
		)
		(stroke
			(width 0)
			(type default)
		)
	)
	(wire
		(pts
			(xy 292.1 205.74) (xy 274.32 205.74)
		)
		(stroke
			(width 0)
			(type default)
		)
	)
	(wire
		(pts
			(xy 292.1 275.59) (xy 295.91 275.59)
		)
		(stroke
			(width 0)
			(type default)
		)
	)
	(bus
		(pts
			(xy 58.42 93.98) (xy 58.42 91.44)
		)
		(stroke
			(width 0)
			(type default)
		)
	)
	(bus
		(pts
			(xy 384.81 44.45) (xy 384.81 41.91)
		)
		(stroke
			(width 0)
			(type default)
		)
	)
	(wire
		(pts
			(xy 322.58 93.98) (xy 328.93 93.98)
		)
		(stroke
			(width 0)
			(type default)
		)
	)
	(wire
		(pts
			(xy 59.69 95.25) (xy 82.55 95.25)
		)
		(stroke
			(width 0)
			(type default)
		)
	)
	(bus
		(pts
			(xy 246.38 171.45) (xy 246.38 173.99)
		)
		(stroke
			(width 0)
			(type default)
		)
	)
	(polyline
		(pts
			(xy 13.97 133.35) (xy 203.2 133.35)
		)
		(stroke
			(width 0)
			(type default)
		)
	)
	(wire
		(pts
			(xy 336.55 200.66) (xy 353.06 200.66)
		)
		(stroke
			(width 0)
			(type default)
		)
	)
	(bus
		(pts
			(xy 382.27 166.37) (xy 382.27 168.91)
		)
		(stroke
			(width 0)
			(type default)
		)
	)
	(bus
		(pts
			(xy 43.18 142.24) (xy 43.18 162.56)
		)
		(stroke
			(width 0)
			(type default)
		)
	)
	(bus
		(pts
			(xy 259.08 74.93) (xy 332.74 74.93)
		)
		(stroke
			(width 0)
			(type default)
		)
	)
	(bus
		(pts
			(xy 125.73 143.51) (xy 125.73 162.56)
		)
		(stroke
			(width 0)
			(type default)
		)
	)
	(wire
		(pts
			(xy 405.13 93.98) (xy 405.13 96.52)
		)
		(stroke
			(width 0)
			(type default)
		)
	)
	(wire
		(pts
			(xy 115.57 182.88) (xy 113.03 182.88)
		)
		(stroke
			(width 0)
			(type default)
		)
	)
	(wire
		(pts
			(xy 306.07 53.34) (xy 307.34 53.34)
		)
		(stroke
			(width 0)
			(type default)
		)
	)
	(wire
		(pts
			(xy 381 113.03) (xy 381 115.57)
		)
		(stroke
			(width 0)
			(type default)
		)
	)
	(bus
		(pts
			(xy 246.38 199.39) (xy 246.38 201.93)
		)
		(stroke
			(width 0)
			(type default)
		)
	)
	(wire
		(pts
			(xy 76.2 193.04) (xy 87.63 193.04)
		)
		(stroke
			(width 0)
			(type default)
		)
	)
	(bus
		(pts
			(xy 125.73 162.56) (xy 125.73 181.61)
		)
		(stroke
			(width 0)
			(type default)
		)
	)
	(bus
		(pts
			(xy 245.11 39.37) (xy 245.11 36.83)
		)
		(stroke
			(width 0)
			(type default)
		)
	)
	(wire
		(pts
			(xy 335.28 91.44) (xy 377.19 91.44)
		)
		(stroke
			(width 0)
			(type default)
		)
	)
	(bus
		(pts
			(xy 43.18 162.56) (xy 43.18 181.61)
		)
		(stroke
			(width 0)
			(type default)
		)
	)
	(wire
		(pts
			(xy 115.57 201.93) (xy 113.03 201.93)
		)
		(stroke
			(width 0)
			(type default)
		)
	)
	(wire
		(pts
			(xy 377.19 97.79) (xy 377.19 99.695)
		)
		(stroke
			(width 0)
			(type default)
		)
	)
	(bus
		(pts
			(xy 245.11 44.45) (xy 245.11 46.99)
		)
		(stroke
			(width 0)
			(type default)
		)
	)
	(wire
		(pts
			(xy 247.65 167.64) (xy 264.16 167.64)
		)
		(stroke
			(width 0)
			(type default)
		)
	)
	(wire
		(pts
			(xy 292.1 193.04) (xy 274.32 193.04)
		)
		(stroke
			(width 0)
			(type default)
		)
	)
	(bus
		(pts
			(xy 245.11 44.45) (xy 245.11 41.91)
		)
		(stroke
			(width 0)
			(type default)
		)
	)
	(bus
		(pts
			(xy 52.07 26.67) (xy 57.15 26.67)
		)
		(stroke
			(width 0)
			(type default)
		)
	)
	(wire
		(pts
			(xy 223.52 262.89) (xy 223.52 265.43)
		)
		(stroke
			(width 0)
			(type default)
		)
	)
	(wire
		(pts
			(xy 387.35 91.44) (xy 384.81 91.44)
		)
		(stroke
			(width 0)
			(type default)
		)
	)
	(wire
		(pts
			(xy 234.95 257.81) (xy 254 257.81)
		)
		(stroke
			(width 0)
			(type default)
		)
	)
	(bus
		(pts
			(xy 266.7 231.14) (xy 266.7 233.68)
		)
		(stroke
			(width 0)
			(type default)
		)
	)
	(wire
		(pts
			(xy 336.55 170.18) (xy 353.06 170.18)
		)
		(stroke
			(width 0)
			(type default)
		)
	)
	(wire
		(pts
			(xy 224.79 262.89) (xy 223.52 262.89)
		)
		(stroke
			(width 0)
			(type default)
		)
	)
	(bus
		(pts
			(xy 312.42 247.65) (xy 313.69 248.92)
		)
		(stroke
			(width 0)
			(type default)
		)
	)
	(wire
		(pts
			(xy 170.18 242.57) (xy 177.8 242.57)
		)
		(stroke
			(width 0)
			(type default)
		)
	)
	(wire
		(pts
			(xy 132.08 151.13) (xy 132.08 154.94)
		)
		(stroke
			(width 0)
			(type default)
		)
	)
	(bus
		(pts
			(xy 335.28 161.29) (xy 335.28 163.83)
		)
		(stroke
			(width 0)
			(type default)
		)
	)
	(polyline
		(pts
			(xy 406.4 127) (xy 209.55 127)
		)
		(stroke
			(width 0)
			(type default)
		)
	)
	(wire
		(pts
			(xy 234.95 267.97) (xy 254 267.97)
		)
		(stroke
			(width 0)
			(type default)
		)
	)
	(wire
		(pts
			(xy 116.84 38.1) (xy 135.89 38.1)
		)
		(stroke
			(width 0)
			(type default)
		)
	)
	(wire
		(pts
			(xy 58.42 38.1) (xy 82.55 38.1)
		)
		(stroke
			(width 0)
			(type default)
		)
	)
	(wire
		(pts
			(xy 72.39 242.57) (xy 72.39 245.11)
		)
		(stroke
			(width 0)
			(type default)
		)
	)
	(bus
		(pts
			(xy 382.27 176.53) (xy 382.27 179.07)
		)
		(stroke
			(width 0)
			(type default)
		)
	)
	(wire
		(pts
			(xy 295.91 273.05) (xy 295.91 275.59)
		)
		(stroke
			(width 0)
			(type default)
		)
	)
	(wire
		(pts
			(xy 100.33 173.99) (xy 104.14 173.99)
		)
		(stroke
			(width 0)
			(type default)
		)
	)
	(bus
		(pts
			(xy 246.38 191.77) (xy 246.38 194.31)
		)
		(stroke
			(width 0)
			(type default)
		)
	)
	(wire
		(pts
			(xy 198.12 163.83) (xy 195.58 163.83)
		)
		(stroke
			(width 0)
			(type default)
		)
	)
	(bus
		(pts
			(xy 335.28 163.83) (xy 335.28 166.37)
		)
		(stroke
			(width 0)
			(type default)
		)
	)
	(wire
		(pts
			(xy 381 190.5) (xy 363.22 190.5)
		)
		(stroke
			(width 0)
			(type default)
		)
	)
	(bus
		(pts
			(xy 266.7 236.22) (xy 266.7 238.76)
		)
		(stroke
			(width 0)
			(type default)
		)
	)
	(bus
		(pts
			(xy 335.28 194.31) (xy 335.28 196.85)
		)
		(stroke
			(width 0)
			(type default)
		)
	)
	(wire
		(pts
			(xy 179.07 260.35) (xy 179.07 261.62)
		)
		(stroke
			(width 0)
			(type default)
		)
	)
	(wire
		(pts
			(xy 179.07 182.88) (xy 190.5 182.88)
		)
		(stroke
			(width 0)
			(type default)
		)
	)
	(wire
		(pts
			(xy 308.61 241.3) (xy 308.61 240.03)
		)
		(stroke
			(width 0)
			(type default)
		)
	)
	(wire
		(pts
			(xy 116.84 40.64) (xy 120.65 40.64)
		)
		(stroke
			(width 0)
			(type default)
		)
	)
	(wire
		(pts
			(xy 58.42 35.56) (xy 82.55 35.56)
		)
		(stroke
			(width 0)
			(type default)
		)
	)
	(bus
		(pts
			(xy 384.81 26.67) (xy 384.81 31.75)
		)
		(stroke
			(width 0)
			(type default)
		)
	)
	(wire
		(pts
			(xy 105.41 100.33) (xy 105.41 109.22)
		)
		(stroke
			(width 0)
			(type default)
		)
	)
	(wire
		(pts
			(xy 46.99 280.67) (xy 57.15 280.67)
		)
		(stroke
			(width 0)
			(type default)
		)
	)
	(bus
		(pts
			(xy 125.73 200.66) (xy 125.73 218.44)
		)
		(stroke
			(width 0)
			(type default)
		)
	)
	(bus
		(pts
			(xy 382.27 179.07) (xy 382.27 186.69)
		)
		(stroke
			(width 0)
			(type default)
		)
	)
	(wire
		(pts
			(xy 59.69 90.17) (xy 82.55 90.17)
		)
		(stroke
			(width 0)
			(type default)
		)
	)
	(wire
		(pts
			(xy 246.38 35.56) (xy 274.32 35.56)
		)
		(stroke
			(width 0)
			(type default)
		)
	)
	(wire
		(pts
			(xy 336.55 193.04) (xy 353.06 193.04)
		)
		(stroke
			(width 0)
			(type default)
		)
	)
	(wire
		(pts
			(xy 223.52 257.81) (xy 223.52 260.35)
		)
		(stroke
			(width 0)
			(type default)
		)
	)
	(wire
		(pts
			(xy 59.69 212.09) (xy 71.12 212.09)
		)
		(stroke
			(width 0)
			(type default)
		)
	)
	(wire
		(pts
			(xy 377.19 91.44) (xy 377.19 92.71)
		)
		(stroke
			(width 0)
			(type default)
		)
	)
	(wire
		(pts
			(xy 115.57 219.71) (xy 113.03 219.71)
		)
		(stroke
			(width 0)
			(type default)
		)
	)
	(wire
		(pts
			(xy 317.5 35.56) (xy 351.79 35.56)
		)
		(stroke
			(width 0)
			(type default)
		)
	)
	(wire
		(pts
			(xy 256.54 260.35) (xy 279.4 260.35)
		)
		(stroke
			(width 0)
			(type default)
		)
	)
	(wire
		(pts
			(xy 111.76 52.07) (xy 111.76 54.61)
		)
		(stroke
			(width 0)
			(type default)
		)
	)
	(bus
		(pts
			(xy 334.01 90.17) (xy 334.01 76.2)
		)
		(stroke
			(width 0)
			(type default)
		)
	)
	(wire
		(pts
			(xy 72.39 242.57) (xy 76.2 242.57)
		)
		(stroke
			(width 0)
			(type default)
		)
	)
	(wire
		(pts
			(xy 287.02 110.49) (xy 287.02 113.03)
		)
		(stroke
			(width 0)
			(type default)
		)
	)
	(wire
		(pts
			(xy 223.52 260.35) (xy 223.52 262.89)
		)
		(stroke
			(width 0)
			(type default)
		)
	)
	(bus
		(pts
			(xy 335.28 179.07) (xy 335.28 181.61)
		)
		(stroke
			(width 0)
			(type default)
		)
	)
	(bus
		(pts
			(xy 383.54 25.4) (xy 384.81 26.67)
		)
		(stroke
			(width 0)
			(type default)
		)
	)
	(bus
		(pts
			(xy 384.81 31.75) (xy 384.81 34.29)
		)
		(stroke
			(width 0)
			(type default)
		)
	)
	(wire
		(pts
			(xy 127 182.88) (xy 179.07 182.88)
		)
		(stroke
			(width 0)
			(type default)
		)
	)
	(wire
		(pts
			(xy 198.12 220.98) (xy 198.12 219.71)
		)
		(stroke
			(width 0)
			(type default)
		)
	)
	(wire
		(pts
			(xy 179.07 200.66) (xy 179.07 201.93)
		)
		(stroke
			(width 0)
			(type default)
		)
	)
	(bus
		(pts
			(xy 255.27 256.54) (xy 255.27 250.19)
		)
		(stroke
			(width 0)
			(type default)
		)
	)
	(wire
		(pts
			(xy 292.1 187.96) (xy 274.32 187.96)
		)
		(stroke
			(width 0)
			(type default)
		)
	)
	(wire
		(pts
			(xy 365.76 162.56) (xy 365.76 182.88)
		)
		(stroke
			(width 0)
			(type default)
		)
	)
	(wire
		(pts
			(xy 356.87 48.26) (xy 383.54 48.26)
		)
		(stroke
			(width 0)
			(type default)
		)
	)
	(wire
		(pts
			(xy 276.86 200.66) (xy 276.86 212.09)
		)
		(stroke
			(width 0)
			(type default)
		)
	)
	(wire
		(pts
			(xy 140.97 30.48) (xy 163.83 30.48)
		)
		(stroke
			(width 0)
			(type default)
		)
	)
	(wire
		(pts
			(xy 59.69 154.94) (xy 71.12 154.94)
		)
		(stroke
			(width 0)
			(type default)
		)
	)
	(wire
		(pts
			(xy 381 175.26) (xy 363.22 175.26)
		)
		(stroke
			(width 0)
			(type default)
		)
	)
	(bus
		(pts
			(xy 236.22 248.92) (xy 254 248.92)
		)
		(stroke
			(width 0)
			(type default)
		)
	)
	(wire
		(pts
			(xy 132.08 189.23) (xy 132.08 193.04)
		)
		(stroke
			(width 0)
			(type default)
		)
	)
	(wire
		(pts
			(xy 158.75 154.94) (xy 170.18 154.94)
		)
		(stroke
			(width 0)
			(type default)
		)
	)
	(wire
		(pts
			(xy 336.55 190.5) (xy 353.06 190.5)
		)
		(stroke
			(width 0)
			(type default)
		)
	)
	(wire
		(pts
			(xy 374.65 113.03) (xy 381 113.03)
		)
		(stroke
			(width 0)
			(type default)
		)
	)
	(wire
		(pts
			(xy 295.91 265.43) (xy 295.91 267.97)
		)
		(stroke
			(width 0)
			(type default)
		)
	)
	(bus
		(pts
			(xy 246.38 149.86) (xy 292.1 149.86)
		)
		(stroke
			(width 0)
			(type default)
		)
	)
	(wire
		(pts
			(xy 96.52 201.93) (xy 107.95 201.93)
		)
		(stroke
			(width 0)
			(type default)
		)
	)
	(wire
		(pts
			(xy 116.84 30.48) (xy 135.89 30.48)
		)
		(stroke
			(width 0)
			(type default)
		)
	)
	(wire
		(pts
			(xy 182.88 154.94) (xy 186.69 154.94)
		)
		(stroke
			(width 0)
			(type default)
		)
	)
	(bus
		(pts
			(xy 312.42 236.22) (xy 312.42 238.76)
		)
		(stroke
			(width 0)
			(type default)
		)
	)
	(wire
		(pts
			(xy 292.1 180.34) (xy 274.32 180.34)
		)
		(stroke
			(width 0)
			(type default)
		)
	)
	(wire
		(pts
			(xy 142.24 173.99) (xy 153.67 173.99)
		)
		(stroke
			(width 0)
			(type default)
		)
	)
	(wire
		(pts
			(xy 279.4 48.26) (xy 307.34 48.26)
		)
		(stroke
			(width 0)
			(type default)
		)
	)
	(bus
		(pts
			(xy 163.83 26.67) (xy 57.15 26.67)
		)
		(stroke
			(width 0)
			(type default)
		)
	)
	(wire
		(pts
			(xy 118.11 109.22) (xy 118.11 100.33)
		)
		(stroke
			(width 0)
			(type default)
		)
	)
	(wire
		(pts
			(xy 246.38 43.18) (xy 274.32 43.18)
		)
		(stroke
			(width 0)
			(type default)
		)
	)
	(wire
		(pts
			(xy 137.16 252.73) (xy 139.7 252.73)
		)
		(stroke
			(width 0)
			(type default)
		)
	)
	(wire
		(pts
			(xy 107.95 271.78) (xy 105.41 271.78)
		)
		(stroke
			(width 0)
			(type default)
		)
	)
	(wire
		(pts
			(xy 384.81 91.44) (xy 384.81 93.98)
		)
		(stroke
			(width 0)
			(type default)
		)
	)
	(bus
		(pts
			(xy 234.95 149.86) (xy 246.38 149.86)
		)
		(stroke
			(width 0)
			(type default)
		)
	)
	(wire
		(pts
			(xy 246.38 48.26) (xy 274.32 48.26)
		)
		(stroke
			(width 0)
			(type default)
		)
	)
	(wire
		(pts
			(xy 68.58 267.97) (xy 68.58 273.05)
		)
		(stroke
			(width 0)
			(type default)
		)
	)
	(polyline
		(pts
			(xy 203.2 228.6) (xy 203.2 133.35)
		)
		(stroke
			(width 0)
			(type default)
		)
	)
	(bus
		(pts
			(xy 335.28 186.69) (xy 335.28 189.23)
		)
		(stroke
			(width 0)
			(type default)
		)
	)
	(wire
		(pts
			(xy 104.14 173.99) (xy 104.14 175.26)
		)
		(stroke
			(width 0)
			(type default)
		)
	)
	(wire
		(pts
			(xy 328.93 91.44) (xy 328.93 93.98)
		)
		(stroke
			(width 0)
			(type default)
		)
	)
	(wire
		(pts
			(xy 234.95 270.51) (xy 254 270.51)
		)
		(stroke
			(width 0)
			(type default)
		)
	)
	(wire
		(pts
			(xy 247.65 208.28) (xy 264.16 208.28)
		)
		(stroke
			(width 0)
			(type default)
		)
	)
	(bus
		(pts
			(xy 246.38 194.31) (xy 246.38 196.85)
		)
		(stroke
			(width 0)
			(type default)
		)
	)
	(bus
		(pts
			(xy 335.28 176.53) (xy 335.28 179.07)
		)
		(stroke
			(width 0)
			(type default)
		)
	)
	(wire
		(pts
			(xy 247.65 160.02) (xy 264.16 160.02)
		)
		(stroke
			(width 0)
			(type default)
		)
	)
	(wire
		(pts
			(xy 276.86 162.56) (xy 274.32 162.56)
		)
		(stroke
			(width 0)
			(type default)
		)
	)
	(wire
		(pts
			(xy 97.79 250.19) (xy 96.52 250.19)
		)
		(stroke
			(width 0)
			(type default)
		)
	)
	(wire
		(pts
			(xy 93.98 252.73) (xy 97.79 252.73)
		)
		(stroke
			(width 0)
			(type default)
		)
	)
	(wire
		(pts
			(xy 140.97 92.71) (xy 165.1 92.71)
		)
		(stroke
			(width 0)
			(type default)
		)
	)
	(bus
		(pts
			(xy 250.19 74.93) (xy 259.08 74.93)
		)
		(stroke
			(width 0)
			(type default)
		)
	)
	(bus
		(pts
			(xy 254 248.92) (xy 255.27 250.19)
		)
		(stroke
			(width 0)
			(type default)
		)
	)
	(bus
		(pts
			(xy 246.38 161.29) (xy 246.38 163.83)
		)
		(stroke
			(width 0)
			(type default)
		)
	)
	(wire
		(pts
			(xy 224.79 265.43) (xy 223.52 265.43)
		)
		(stroke
			(width 0)
			(type default)
		)
	)
	(wire
		(pts
			(xy 170.18 245.11) (xy 170.18 242.57)
		)
		(stroke
			(width 0)
			(type default)
		)
	)
	(wire
		(pts
			(xy 96.52 200.66) (xy 96.52 201.93)
		)
		(stroke
			(width 0)
			(type default)
		)
	)
	(wire
		(pts
			(xy 397.51 91.44) (xy 405.13 91.44)
		)
		(stroke
			(width 0)
			(type default)
		)
	)
	(wire
		(pts
			(xy 104.14 212.09) (xy 104.14 213.36)
		)
		(stroke
			(width 0)
			(type default)
		)
	)
	(wire
		(pts
			(xy 381 198.12) (xy 363.22 198.12)
		)
		(stroke
			(width 0)
			(type default)
		)
	)
	(wire
		(pts
			(xy 365.76 162.56) (xy 365.76 160.02)
		)
		(stroke
			(width 0)
			(type default)
		)
	)
	(wire
		(pts
			(xy 381 172.72) (xy 363.22 172.72)
		)
		(stroke
			(width 0)
			(type default)
		)
	)
	(wire
		(pts
			(xy 198.12 201.93) (xy 195.58 201.93)
		)
		(stroke
			(width 0)
			(type default)
		)
	)
	(bus
		(pts
			(xy 335.28 196.85) (xy 335.28 199.39)
		)
		(stroke
			(width 0)
			(type default)
		)
	)
	(wire
		(pts
			(xy 54.61 212.09) (xy 49.53 212.09)
		)
		(stroke
			(width 0)
			(type default)
		)
	)
	(wire
		(pts
			(xy 87.63 38.1) (xy 106.68 38.1)
		)
		(stroke
			(width 0)
			(type default)
		)
	)
	(wire
		(pts
			(xy 381 177.8) (xy 363.22 177.8)
		)
		(stroke
			(width 0)
			(type default)
		)
	)
	(wire
		(pts
			(xy 302.26 81.28) (xy 302.26 83.82)
		)
		(stroke
			(width 0)
			(type default)
		)
	)
	(wire
		(pts
			(xy 328.93 93.98) (xy 328.93 96.52)
		)
		(stroke
			(width 0)
			(type default)
		)
	)
	(bus
		(pts
			(xy 381 149.86) (xy 382.27 151.13)
		)
		(stroke
			(width 0)
			(type default)
		)
	)
	(wire
		(pts
			(xy 137.16 154.94) (xy 132.08 154.94)
		)
		(stroke
			(width 0)
			(type default)
		)
	)
	(wire
		(pts
			(xy 302.26 88.9) (xy 302.26 91.44)
		)
		(stroke
			(width 0)
			(type default)
		)
	)
	(wire
		(pts
			(xy 223.52 270.51) (xy 223.52 273.05)
		)
		(stroke
			(width 0)
			(type default)
		)
	)
	(wire
		(pts
			(xy 87.63 30.48) (xy 106.68 30.48)
		)
		(stroke
			(width 0)
			(type default)
		)
	)
	(wire
		(pts
			(xy 96.52 163.83) (xy 107.95 163.83)
		)
		(stroke
			(width 0)
			(type default)
		)
	)
	(wire
		(pts
			(xy 234.95 180.34) (xy 234.95 182.88)
		)
		(stroke
			(width 0)
			(type default)
		)
	)
	(wire
		(pts
			(xy 256.54 273.05) (xy 279.4 273.05)
		)
		(stroke
			(width 0)
			(type default)
		)
	)
	(wire
		(pts
			(xy 115.57 165.1) (xy 115.57 163.83)
		)
		(stroke
			(width 0)
			(type default)
		)
	)
	(bus
		(pts
			(xy 255.27 264.16) (xy 255.27 261.62)
		)
		(stroke
			(width 0)
			(type default)
		)
	)
	(wire
		(pts
			(xy 140.97 95.25) (xy 165.1 95.25)
		)
		(stroke
			(width 0)
			(type default)
		)
	)
	(bus
		(pts
			(xy 58.42 91.44) (xy 58.42 88.9)
		)
		(stroke
			(width 0)
			(type default)
		)
	)
	(wire
		(pts
			(xy 246.38 234.95) (xy 265.43 234.95)
		)
		(stroke
			(width 0)
			(type default)
		)
	)
	(bus
		(pts
			(xy 382.27 194.31) (xy 382.27 196.85)
		)
		(stroke
			(width 0)
			(type default)
		)
	)
	(bus
		(pts
			(xy 34.29 142.24) (xy 43.18 142.24)
		)
		(stroke
			(width 0)
			(type default)
		)
	)
	(wire
		(pts
			(xy 292.1 208.28) (xy 274.32 208.28)
		)
		(stroke
			(width 0)
			(type default)
		)
	)
	(bus
		(pts
			(xy 255.27 271.78) (xy 255.27 269.24)
		)
		(stroke
			(width 0)
			(type default)
		)
	)
	(wire
		(pts
			(xy 118.11 43.18) (xy 116.84 43.18)
		)
		(stroke
			(width 0)
			(type default)
		)
	)
	(wire
		(pts
			(xy 182.88 173.99) (xy 186.69 173.99)
		)
		(stroke
			(width 0)
			(type default)
		)
	)
	(wire
		(pts
			(xy 299.72 110.49) (xy 306.07 110.49)
		)
		(stroke
			(width 0)
			(type default)
		)
	)
	(wire
		(pts
			(xy 138.43 260.35) (xy 139.7 260.35)
		)
		(stroke
			(width 0)
			(type default)
		)
	)
	(bus
		(pts
			(xy 255.27 261.62) (xy 255.27 259.08)
		)
		(stroke
			(width 0)
			(type default)
		)
	)
	(wire
		(pts
			(xy 44.45 219.71) (xy 96.52 219.71)
		)
		(stroke
			(width 0)
			(type default)
		)
	)
	(wire
		(pts
			(xy 49.53 170.18) (xy 49.53 173.99)
		)
		(stroke
			(width 0)
			(type default)
		)
	)
	(wire
		(pts
			(xy 198.12 219.71) (xy 195.58 219.71)
		)
		(stroke
			(width 0)
			(type default)
		)
	)
	(bus
		(pts
			(xy 255.27 259.08) (xy 255.27 256.54)
		)
		(stroke
			(width 0)
			(type default)
		)
	)
	(wire
		(pts
			(xy 76.2 257.81) (xy 76.2 250.19)
		)
		(stroke
			(width 0)
			(type default)
		)
	)
	(wire
		(pts
			(xy 381 110.49) (xy 381 113.03)
		)
		(stroke
			(width 0)
			(type default)
		)
	)
	(bus
		(pts
			(xy 335.28 171.45) (xy 335.28 176.53)
		)
		(stroke
			(width 0)
			(type default)
		)
	)
	(wire
		(pts
			(xy 124.46 267.97) (xy 124.46 257.81)
		)
		(stroke
			(width 0)
			(type default)
		)
	)
	(wire
		(pts
			(xy 186.69 173.99) (xy 186.69 175.26)
		)
		(stroke
			(width 0)
			(type default)
		)
	)
	(wire
		(pts
			(xy 354.33 100.965) (xy 354.33 102.87)
		)
		(stroke
			(width 0)
			(type default)
		)
	)
	(wire
		(pts
			(xy 381 167.64) (xy 363.22 167.64)
		)
		(stroke
			(width 0)
			(type default)
		)
	)
	(wire
		(pts
			(xy 86.36 242.57) (xy 93.98 242.57)
		)
		(stroke
			(width 0)
			(type default)
		)
	)
	(wire
		(pts
			(xy 96.52 250.19) (xy 96.52 260.35)
		)
		(stroke
			(width 0)
			(type default)
		)
	)
	(wire
		(pts
			(xy 336.55 165.1) (xy 353.06 165.1)
		)
		(stroke
			(width 0)
			(type default)
		)
	)
	(wire
		(pts
			(xy 256.54 257.81) (xy 279.4 257.81)
		)
		(stroke
			(width 0)
			(type default)
		)
	)
	(wire
		(pts
			(xy 292.1 198.12) (xy 274.32 198.12)
		)
		(stroke
			(width 0)
			(type default)
		)
	)
	(bus
		(pts
			(xy 242.57 25.4) (xy 245.11 25.4)
		)
		(stroke
			(width 0)
			(type default)
		)
	)
	(bus
		(pts
			(xy 165.1 29.21) (xy 165.1 31.75)
		)
		(stroke
			(width 0)
			(type default)
		)
	)
	(wire
		(pts
			(xy 276.86 170.18) (xy 276.86 167.64)
		)
		(stroke
			(width 0)
			(type default)
		)
	)
	(bus
		(pts
			(xy 293.37 191.77) (xy 293.37 194.31)
		)
		(stroke
			(width 0)
			(type default)
		)
	)
	(wire
		(pts
			(xy 129.54 242.57) (xy 137.16 242.57)
		)
		(stroke
			(width 0)
			(type default)
		)
	)
	(wire
		(pts
			(xy 59.69 92.71) (xy 82.55 92.71)
		)
		(stroke
			(width 0)
			(type default)
		)
	)
	(bus
		(pts
			(xy 293.37 189.23) (xy 293.37 191.77)
		)
		(stroke
			(width 0)
			(type default)
		)
	)
	(bus
		(pts
			(xy 246.38 179.07) (xy 246.38 184.15)
		)
		(stroke
			(width 0)
			(type default)
		)
	)
	(wire
		(pts
			(xy 234.95 260.35) (xy 254 260.35)
		)
		(stroke
			(width 0)
			(type default)
		)
	)
	(wire
		(pts
			(xy 111.76 107.95) (xy 111.76 109.22)
		)
		(stroke
			(width 0)
			(type default)
		)
	)
	(wire
		(pts
			(xy 111.76 52.07) (xy 118.11 52.07)
		)
		(stroke
			(width 0)
			(type default)
		)
	)
	(wire
		(pts
			(xy 356.87 40.64) (xy 383.54 40.64)
		)
		(stroke
			(width 0)
			(type default)
		)
	)
	(wire
		(pts
			(xy 96.52 219.71) (xy 107.95 219.71)
		)
		(stroke
			(width 0)
			(type default)
		)
	)
	(wire
		(pts
			(xy 279.4 110.49) (xy 279.4 114.3)
		)
		(stroke
			(width 0)
			(type default)
		)
	)
	(wire
		(pts
			(xy 234.95 182.88) (xy 264.16 182.88)
		)
		(stroke
			(width 0)
			(type default)
		)
	)
	(bus
		(pts
			(xy 382.27 189.23) (xy 382.27 191.77)
		)
		(stroke
			(width 0)
			(type default)
		)
	)
	(wire
		(pts
			(xy 295.91 275.59) (xy 295.91 278.13)
		)
		(stroke
			(width 0)
			(type default)
		)
	)
	(polyline
		(pts
			(xy 209.55 133.35) (xy 209.55 217.17)
		)
		(stroke
			(width 0)
			(type default)
		)
	)
	(wire
		(pts
			(xy 356.87 43.18) (xy 383.54 43.18)
		)
		(stroke
			(width 0)
			(type default)
		)
	)
	(wire
		(pts
			(xy 256.54 270.51) (xy 279.4 270.51)
		)
		(stroke
			(width 0)
			(type default)
		)
	)
	(bus
		(pts
			(xy 245.11 25.4) (xy 245.11 34.29)
		)
		(stroke
			(width 0)
			(type default)
		)
	)
	(wire
		(pts
			(xy 247.65 185.42) (xy 264.16 185.42)
		)
		(stroke
			(width 0)
			(type default)
		)
	)
	(bus
		(pts
			(xy 166.37 91.44) (xy 166.37 93.98)
		)
		(stroke
			(width 0)
			(type default)
		)
	)
	(wire
		(pts
			(xy 158.75 212.09) (xy 170.18 212.09)
		)
		(stroke
			(width 0)
			(type default)
		)
	)
	(wire
		(pts
			(xy 132.08 170.18) (xy 132.08 173.99)
		)
		(stroke
			(width 0)
			(type default)
		)
	)
	(wire
		(pts
			(xy 295.91 262.89) (xy 295.91 265.43)
		)
		(stroke
			(width 0)
			(type default)
		)
	)
	(wire
		(pts
			(xy 336.55 182.88) (xy 353.06 182.88)
		)
		(stroke
			(width 0)
			(type default)
		)
	)
	(wire
		(pts
			(xy 384.81 93.98) (xy 387.35 93.98)
		)
		(stroke
			(width 0)
			(type default)
		)
	)
	(wire
		(pts
			(xy 365.76 162.56) (xy 363.22 162.56)
		)
		(stroke
			(width 0)
			(type default)
		)
	)
	(wire
		(pts
			(xy 292.1 175.26) (xy 274.32 175.26)
		)
		(stroke
			(width 0)
			(type default)
		)
	)
	(wire
		(pts
			(xy 279.4 100.965) (xy 279.4 102.87)
		)
		(stroke
			(width 0)
			(type default)
		)
	)
	(wire
		(pts
			(xy 363.22 200.66) (xy 365.76 200.66)
		)
		(stroke
			(width 0)
			(type default)
		)
	)
	(wire
		(pts
			(xy 317.5 40.64) (xy 351.79 40.64)
		)
		(stroke
			(width 0)
			(type default)
		)
	)
	(wire
		(pts
			(xy 179.07 250.19) (xy 179.07 260.35)
		)
		(stroke
			(width 0)
			(type default)
		)
	)
	(polyline
		(pts
			(xy 406.4 133.35) (xy 209.55 133.35)
		)
		(stroke
			(width 0)
			(type default)
		)
	)
	(wire
		(pts
			(xy 247.65 180.34) (xy 264.16 180.34)
		)
		(stroke
			(width 0)
			(type default)
		)
	)
	(bus
		(pts
			(xy 335.28 168.91) (xy 335.28 171.45)
		)
		(stroke
			(width 0)
			(type default)
		)
	)
	(wire
		(pts
			(xy 87.63 92.71) (xy 106.68 92.71)
		)
		(stroke
			(width 0)
			(type default)
		)
	)
	(bus
		(pts
			(xy 312.42 233.68) (xy 312.42 236.22)
		)
		(stroke
			(width 0)
			(type default)
		)
	)
	(bus
		(pts
			(xy 246.38 163.83) (xy 246.38 166.37)
		)
		(stroke
			(width 0)
			(type default)
		)
	)
	(bus
		(pts
			(xy 335.28 181.61) (xy 335.28 184.15)
		)
		(stroke
			(width 0)
			(type default)
		)
	)
	(wire
		(pts
			(xy 87.63 90.17) (xy 106.68 90.17)
		)
		(stroke
			(width 0)
			(type default)
		)
	)
	(bus
		(pts
			(xy 293.37 196.85) (xy 293.37 201.93)
		)
		(stroke
			(width 0)
			(type default)
		)
	)
	(wire
		(pts
			(xy 336.55 185.42) (xy 353.06 185.42)
		)
		(stroke
			(width 0)
			(type default)
		)
	)
	(wire
		(pts
			(xy 354.33 119.38) (xy 354.33 121.92)
		)
		(stroke
			(width 0)
			(type default)
		)
	)
	(wire
		(pts
			(xy 246.38 240.03) (xy 262.89 240.03)
		)
		(stroke
			(width 0)
			(type default)
		)
	)
	(wire
		(pts
			(xy 116.84 33.02) (xy 135.89 33.02)
		)
		(stroke
			(width 0)
			(type default)
		)
	)
	(wire
		(pts
			(xy 62.23 273.05) (xy 68.58 273.05)
		)
		(stroke
			(width 0)
			(type default)
		)
	)
	(wire
		(pts
			(xy 336.55 198.12) (xy 353.06 198.12)
		)
		(stroke
			(width 0)
			(type default)
		)
	)
	(wire
		(pts
			(xy 292.1 190.5) (xy 274.32 190.5)
		)
		(stroke
			(width 0)
			(type default)
		)
	)
	(bus
		(pts
			(xy 312.42 238.76) (xy 312.42 247.65)
		)
		(stroke
			(width 0)
			(type default)
		)
	)
	(wire
		(pts
			(xy 292.1 203.2) (xy 274.32 203.2)
		)
		(stroke
			(width 0)
			(type default)
		)
	)
	(wire
		(pts
			(xy 120.65 40.64) (xy 120.65 43.18)
		)
		(stroke
			(width 0)
			(type default)
		)
	)
	(bus
		(pts
			(xy 382.27 168.91) (xy 382.27 171.45)
		)
		(stroke
			(width 0)
			(type default)
		)
	)
	(bus
		(pts
			(xy 166.37 86.36) (xy 166.37 88.9)
		)
		(stroke
			(width 0)
			(type default)
		)
	)
	(wire
		(pts
			(xy 132.08 207.01) (xy 132.08 212.09)
		)
		(stroke
			(width 0)
			(type default)
		)
	)
	(wire
		(pts
			(xy 87.63 35.56) (xy 106.68 35.56)
		)
		(stroke
			(width 0)
			(type default)
		)
	)
	(bus
		(pts
			(xy 335.28 191.77) (xy 335.28 194.31)
		)
		(stroke
			(width 0)
			(type default)
		)
	)
	(wire
		(pts
			(xy 49.53 189.23) (xy 49.53 193.04)
		)
		(stroke
			(width 0)
			(type default)
		)
	)
	(wire
		(pts
			(xy 276.86 182.88) (xy 276.86 170.18)
		)
		(stroke
			(width 0)
			(type default)
		)
	)
	(wire
		(pts
			(xy 374.65 110.49) (xy 381 110.49)
		)
		(stroke
			(width 0)
			(type default)
		)
	)
	(wire
		(pts
			(xy 276.86 182.88) (xy 276.86 200.66)
		)
		(stroke
			(width 0)
			(type default)
		)
	)
	(wire
		(pts
			(xy 165.1 267.97) (xy 165.1 257.81)
		)
		(stroke
			(width 0)
			(type default)
		)
	)
	(wire
		(pts
			(xy 397.51 93.98) (xy 405.13 93.98)
		)
		(stroke
			(width 0)
			(type default)
		)
	)
	(wire
		(pts
			(xy 276.86 167.64) (xy 276.86 165.1)
		)
		(stroke
			(width 0)
			(type default)
		)
	)
	(wire
		(pts
			(xy 137.16 212.09) (xy 132.08 212.09)
		)
		(stroke
			(width 0)
			(type default)
		)
	)
	(bus
		(pts
			(xy 246.38 158.75) (xy 246.38 161.29)
		)
		(stroke
			(width 0)
			(type default)
		)
	)
	(wire
		(pts
			(xy 246.38 229.87) (xy 265.43 229.87)
		)
		(stroke
			(width 0)
			(type default)
		)
	)
	(polyline
		(pts
			(xy 13.97 127) (xy 203.2 127)
		)
		(stroke
			(width 0)
			(type default)
		)
	)
	(wire
		(pts
			(xy 322.58 91.44) (xy 328.93 91.44)
		)
		(stroke
			(width 0)
			(type default)
		)
	)
	(bus
		(pts
			(xy 382.27 151.13) (xy 382.27 163.83)
		)
		(stroke
			(width 0)
			(type default)
		)
	)
	(wire
		(pts
			(xy 302.26 97.79) (xy 302.26 99.695)
		)
		(stroke
			(width 0)
			(type default)
		)
	)
	(wire
		(pts
			(xy 111.76 109.22) (xy 118.11 109.22)
		)
		(stroke
			(width 0)
			(type default)
		)
	)
	(bus
		(pts
			(xy 293.37 204.47) (xy 293.37 207.01)
		)
		(stroke
			(width 0)
			(type default)
		)
	)
	(wire
		(pts
			(xy 234.95 265.43) (xy 254 265.43)
		)
		(stroke
			(width 0)
			(type default)
		)
	)
	(wire
		(pts
			(xy 354.33 107.95) (xy 354.33 110.49)
		)
		(stroke
			(width 0)
			(type default)
		)
	)
	(wire
		(pts
			(xy 292.1 267.97) (xy 295.91 267.97)
		)
		(stroke
			(width 0)
			(type default)
		)
	)
	(wire
		(pts
			(xy 179.07 201.93) (xy 190.5 201.93)
		)
		(stroke
			(width 0)
			(type default)
		)
	)
	(wire
		(pts
			(xy 289.56 110.49) (xy 287.02 110.49)
		)
		(stroke
			(width 0)
			(type default)
		)
	)
	(wire
		(pts
			(xy 86.36 245.11) (xy 86.36 242.57)
		)
		(stroke
			(width 0)
			(type default)
		)
	)
	(bus
		(pts
			(xy 312.42 231.14) (xy 312.42 233.68)
		)
		(stroke
			(width 0)
			(type default)
		)
	)
	(wire
		(pts
			(xy 377.19 81.28) (xy 377.19 83.82)
		)
		(stroke
			(width 0)
			(type default)
		)
	)
	(wire
		(pts
			(xy 198.12 182.88) (xy 195.58 182.88)
		)
		(stroke
			(width 0)
			(type default)
		)
	)
	(wire
		(pts
			(xy 142.24 154.94) (xy 153.67 154.94)
		)
		(stroke
			(width 0)
			(type default)
		)
	)
	(wire
		(pts
			(xy 105.41 109.22) (xy 111.76 109.22)
		)
		(stroke
			(width 0)
			(type default)
		)
	)
	(wire
		(pts
			(xy 44.45 182.88) (xy 96.52 182.88)
		)
		(stroke
			(width 0)
			(type default)
		)
	)
	(polyline
		(pts
			(xy 406.4 63.5) (xy 209.55 63.5)
		)
		(stroke
			(width 0)
			(type default)
		)
	)
	(wire
		(pts
			(xy 106.68 97.79) (xy 101.6 97.79)
		)
		(stroke
			(width 0)
			(type default)
		)
	)
	(wire
		(pts
			(xy 323.85 172.72) (xy 323.85 175.26)
		)
		(stroke
			(width 0)
			(type default)
		)
	)
	(bus
		(pts
			(xy 245.11 25.4) (xy 383.54 25.4)
		)
		(stroke
			(width 0)
			(type default)
		)
	)
	(bus
		(pts
			(xy 382.27 191.77) (xy 382.27 194.31)
		)
		(stroke
			(width 0)
			(type default)
		)
	)
	(wire
		(pts
			(xy 124.46 257.81) (xy 139.7 257.81)
		)
		(stroke
			(width 0)
			(type default)
		)
	)
	(wire
		(pts
			(xy 306.07 53.34) (xy 306.07 54.61)
		)
		(stroke
			(width 0)
			(type default)
		)
	)
	(wire
		(pts
			(xy 260.35 110.49) (xy 279.4 110.49)
		)
		(stroke
			(width 0)
			(type default)
		)
	)
	(bus
		(pts
			(xy 58.42 86.36) (xy 58.42 83.82)
		)
		(stroke
			(width 0)
			(type default)
		)
	)
	(bus
		(pts
			(xy 57.15 29.21) (xy 57.15 26.67)
		)
		(stroke
			(width 0)
			(type default)
		)
	)
	(wire
		(pts
			(xy 223.52 265.43) (xy 223.52 267.97)
		)
		(stroke
			(width 0)
			(type default)
		)
	)
	(wire
		(pts
			(xy 76.2 242.57) (xy 86.36 242.57)
		)
		(stroke
			(width 0)
			(type default)
		)
	)
	(wire
		(pts
			(xy 276.86 162.56) (xy 276.86 160.02)
		)
		(stroke
			(width 0)
			(type default)
		)
	)
	(wire
		(pts
			(xy 138.43 250.19) (xy 138.43 260.35)
		)
		(stroke
			(width 0)
			(type default)
		)
	)
	(polyline
		(pts
			(xy 13.97 228.6) (xy 203.2 228.6)
		)
		(stroke
			(width 0)
			(type default)
		)
	)
	(wire
		(pts
			(xy 247.65 195.58) (xy 264.16 195.58)
		)
		(stroke
			(width 0)
			(type default)
		)
	)
	(wire
		(pts
			(xy 49.53 151.13) (xy 49.53 154.94)
		)
		(stroke
			(width 0)
			(type default)
		)
	)
	(wire
		(pts
			(xy 115.57 220.98) (xy 115.57 219.71)
		)
		(stroke
			(width 0)
			(type default)
		)
	)
	(wire
		(pts
			(xy 247.65 162.56) (xy 264.16 162.56)
		)
		(stroke
			(width 0)
			(type default)
		)
	)
	(wire
		(pts
			(xy 302.26 91.44) (xy 309.88 91.44)
		)
		(stroke
			(width 0)
			(type default)
		)
	)
	(bus
		(pts
			(xy 165.1 27.94) (xy 165.1 29.21)
		)
		(stroke
			(width 0)
			(type default)
		)
	)
	(wire
		(pts
			(xy 140.97 38.1) (xy 163.83 38.1)
		)
		(stroke
			(width 0)
			(type default)
		)
	)
	(wire
		(pts
			(xy 377.19 91.44) (xy 384.81 91.44)
		)
		(stroke
			(width 0)
			(type default)
		)
	)
	(bus
		(pts
			(xy 246.38 168.91) (xy 246.38 171.45)
		)
		(stroke
			(width 0)
			(type default)
		)
	)
	(wire
		(pts
			(xy 336.55 195.58) (xy 353.06 195.58)
		)
		(stroke
			(width 0)
			(type default)
		)
	)
	(bus
		(pts
			(xy 166.37 88.9) (xy 166.37 91.44)
		)
		(stroke
			(width 0)
			(type default)
		)
	)
	(wire
		(pts
			(xy 292.1 177.8) (xy 274.32 177.8)
		)
		(stroke
			(width 0)
			(type default)
		)
	)
	(wire
		(pts
			(xy 246.38 38.1) (xy 274.32 38.1)
		)
		(stroke
			(width 0)
			(type default)
		)
	)
	(wire
		(pts
			(xy 247.65 172.72) (xy 264.16 172.72)
		)
		(stroke
			(width 0)
			(type default)
		)
	)
	(wire
		(pts
			(xy 87.63 33.02) (xy 106.68 33.02)
		)
		(stroke
			(width 0)
			(type default)
		)
	)
	(wire
		(pts
			(xy 93.98 242.57) (xy 93.98 252.73)
		)
		(stroke
			(width 0)
			(type default)
		)
	)
	(wire
		(pts
			(xy 179.07 260.35) (xy 180.34 260.35)
		)
		(stroke
			(width 0)
			(type default)
		)
	)
	(wire
		(pts
			(xy 276.86 165.1) (xy 274.32 165.1)
		)
		(stroke
			(width 0)
			(type default)
		)
	)
	(wire
		(pts
			(xy 312.42 91.44) (xy 309.88 91.44)
		)
		(stroke
			(width 0)
			(type default)
		)
	)
	(bus
		(pts
			(xy 246.38 173.99) (xy 246.38 176.53)
		)
		(stroke
			(width 0)
			(type default)
		)
	)
	(wire
		(pts
			(xy 106.68 43.18) (xy 105.41 43.18)
		)
		(stroke
			(width 0)
			(type default)
		)
	)
	(wire
		(pts
			(xy 115.57 203.2) (xy 115.57 201.93)
		)
		(stroke
			(width 0)
			(type default)
		)
	)
	(bus
		(pts
			(xy 334.01 109.22) (xy 334.01 90.17)
		)
		(stroke
			(width 0)
			(type default)
		)
	)
	(wire
		(pts
			(xy 234.95 273.05) (xy 254 273.05)
		)
		(stroke
			(width 0)
			(type default)
		)
	)
	(bus
		(pts
			(xy 384.81 41.91) (xy 384.81 39.37)
		)
		(stroke
			(width 0)
			(type default)
		)
	)
	(wire
		(pts
			(xy 116.84 95.25) (xy 135.89 95.25)
		)
		(stroke
			(width 0)
			(type default)
		)
	)
	(wire
		(pts
			(xy 105.41 43.18) (xy 105.41 52.07)
		)
		(stroke
			(width 0)
			(type default)
		)
	)
	(wire
		(pts
			(xy 256.54 262.89) (xy 279.4 262.89)
		)
		(stroke
			(width 0)
			(type default)
		)
	)
	(wire
		(pts
			(xy 247.65 165.1) (xy 264.16 165.1)
		)
		(stroke
			(width 0)
			(type default)
		)
	)
	(bus
		(pts
			(xy 246.38 201.93) (xy 246.38 204.47)
		)
		(stroke
			(width 0)
			(type default)
		)
	)
	(wire
		(pts
			(xy 292.1 260.35) (xy 295.91 260.35)
		)
		(stroke
			(width 0)
			(type default)
		)
	)
	(wire
		(pts
			(xy 335.28 110.49) (xy 354.33 110.49)
		)
		(stroke
			(width 0)
			(type default)
		)
	)
	(wire
		(pts
			(xy 182.88 212.09) (xy 186.69 212.09)
		)
		(stroke
			(width 0)
			(type default)
		)
	)
	(wire
		(pts
			(xy 123.19 271.78) (xy 120.65 271.78)
		)
		(stroke
			(width 0)
			(type default)
		)
	)
	(wire
		(pts
			(xy 336.55 162.56) (xy 353.06 162.56)
		)
		(stroke
			(width 0)
			(type default)
		)
	)
	(wire
		(pts
			(xy 105.41 267.97) (xy 105.41 271.78)
		)
		(stroke
			(width 0)
			(type default)
		)
	)
	(bus
		(pts
			(xy 166.37 85.09) (xy 165.1 83.82)
		)
		(stroke
			(width 0)
			(type default)
		)
	)
	(wire
		(pts
			(xy 295.91 278.13) (xy 295.91 279.4)
		)
		(stroke
			(width 0)
			(type default)
		)
	)
	(bus
		(pts
			(xy 384.81 44.45) (xy 384.81 46.99)
		)
		(stroke
			(width 0)
			(type default)
		)
	)
	(wire
		(pts
			(xy 306.07 110.49) (xy 306.07 113.03)
		)
		(stroke
			(width 0)
			(type default)
		)
	)
	(bus
		(pts
			(xy 293.37 194.31) (xy 293.37 196.85)
		)
		(stroke
			(width 0)
			(type default)
		)
	)
	(wire
		(pts
			(xy 140.97 35.56) (xy 163.83 35.56)
		)
		(stroke
			(width 0)
			(type default)
		)
	)
	(label "CW_20PIN_TPDID"
		(at 288.29 48.26 0)
		(effects
			(font
				(size 1.27 1.27)
			)
			(justify left bottom)
		)
	)
	(label "USER_IO.DIP_SW1"
		(at 247.65 232.41 0)
		(effects
			(font
				(size 1.27 1.27)
			)
			(justify left bottom)
		)
	)
	(label "USER_IO.DIP_SW4"
		(at 256.54 267.97 0)
		(effects
			(font
				(size 1.27 1.27)
			)
			(justify left bottom)
		)
	)
	(label "USER_IO.A26"
		(at 278.13 190.5 0)
		(effects
			(font
				(size 1.27 1.27)
			)
			(justify left bottom)
		)
	)
	(label "USER_IO.LED_GREEN0"
		(at 45.72 163.83 0)
		(effects
			(font
				(size 1.27 1.27)
			)
			(justify left bottom)
		)
	)
	(label "PMOD_A.IO1"
		(at 149.86 30.48 0)
		(effects
			(font
				(size 1.27 1.27)
			)
			(justify left bottom)
		)
	)
	(label "USER_IO.DIP_SW4"
		(at 236.22 267.97 0)
		(effects
			(font
				(size 1.27 1.27)
			)
			(justify left bottom)
		)
	)
	(label "CW_20PIN_IO3"
		(at 327.66 45.72 0)
		(effects
			(font
				(size 1.27 1.27)
			)
			(justify left bottom)
		)
	)
	(label "PMOD_B.IO7"
		(at 63.5 87.63 0)
		(effects
			(font
				(size 1.27 1.27)
			)
			(justify left bottom)
		)
	)
	(label "USER_IO.B25"
		(at 337.82 190.5 0)
		(effects
			(font
				(size 1.27 1.27)
			)
			(justify left bottom)
		)
	)
	(label "CW_20PIN_TSCK"
		(at 288.29 43.18 0)
		(effects
			(font
				(size 1.27 1.27)
			)
			(justify left bottom)
		)
	)
	(label "USER_IO.A21"
		(at 248.92 185.42 0)
		(effects
			(font
				(size 1.27 1.27)
			)
			(justify left bottom)
		)
	)
	(label "USER_IO.DIP_SW6"
		(at 292.1 234.95 0)
		(effects
			(font
				(size 1.27 1.27)
			)
			(justify left bottom)
		)
	)
	(label "USER_IO.B9"
		(at 337.82 170.18 0)
		(effects
			(font
				(size 1.27 1.27)
			)
			(justify left bottom)
		)
	)
	(label "USER_IO.A31"
		(at 248.92 198.12 0)
		(effects
			(font
				(size 1.27 1.27)
			)
			(justify left bottom)
		)
	)
	(label "PMOD_A_7"
		(at 96.52 30.48 0)
		(effects
			(font
				(size 1.27 1.27)
			)
			(justify left bottom)
		)
	)
	(label "PMOD_A.IO2"
		(at 149.86 33.02 0)
		(effects
			(font
				(size 1.27 1.27)
			)
			(justify left bottom)
		)
	)
	(label "USER_IO.DIP_SW3"
		(at 247.65 237.49 0)
		(effects
			(font
				(size 1.27 1.27)
			)
			(justify left bottom)
		)
	)
	(label "USER_IO.B5"
		(at 337.82 165.1 0)
		(effects
			(font
				(size 1.27 1.27)
			)
			(justify left bottom)
		)
	)
	(label "FAN_PWM_CTRL_AON"
		(at 68.58 280.67 0)
		(effects
			(font
				(size 1.27 1.27)
			)
			(justify left bottom)
		)
	)
	(label "USER_IO.DIP_SW0"
		(at 247.65 229.87 0)
		(effects
			(font
				(size 1.27 1.27)
			)
			(justify left bottom)
		)
	)
	(label "USER_IO.DIP_SW7"
		(at 256.54 275.59 0)
		(effects
			(font
				(size 1.27 1.27)
			)
			(justify left bottom)
		)
	)
	(label "PMOD_B_10"
		(at 95.25 95.25 0)
		(effects
			(font
				(size 1.27 1.27)
			)
			(justify left bottom)
		)
	)
	(label "USER_IO.B10"
		(at 367.03 170.18 0)
		(effects
			(font
				(size 1.27 1.27)
			)
			(justify left bottom)
		)
	)
	(label "USER_IO.DIP_SW6"
		(at 236.22 273.05 0)
		(effects
			(font
				(size 1.27 1.27)
			)
			(justify left bottom)
		)
	)
	(label "PMOD_A.IO8"
		(at 63.5 33.02 0)
		(effects
			(font
				(size 1.27 1.27)
			)
			(justify left bottom)
		)
	)
	(label "USER_IO.B1"
		(at 337.82 160.02 0)
		(effects
			(font
				(size 1.27 1.27)
			)
			(justify left bottom)
		)
	)
	(label "PMOD_A_1"
		(at 116.84 30.48 0)
		(effects
			(font
				(size 1.27 1.27)
			)
			(justify left bottom)
		)
	)
	(label "USER_IO.DIP_SW3"
		(at 256.54 265.43 0)
		(effects
			(font
				(size 1.27 1.27)
			)
			(justify left bottom)
		)
	)
	(label "USER_IO.A5"
		(at 248.92 165.1 0)
		(effects
			(font
				(size 1.27 1.27)
			)
			(justify left bottom)
		)
	)
	(label "USER_IO.B12"
		(at 367.03 172.72 0)
		(effects
			(font
				(size 1.27 1.27)
			)
			(justify left bottom)
		)
	)
	(label "USER_IO.DIP_SW5"
		(at 236.22 270.51 0)
		(effects
			(font
				(size 1.27 1.27)
			)
			(justify left bottom)
		)
	)
	(label "PMOD_B_4"
		(at 116.84 95.25 0)
		(effects
			(font
				(size 1.27 1.27)
			)
			(justify left bottom)
		)
	)
	(label "USER_IO.A7"
		(at 248.92 167.64 0)
		(effects
			(font
				(size 1.27 1.27)
			)
			(justify left bottom)
		)
	)
	(label "USER_IO.A27"
		(at 248.92 193.04 0)
		(effects
			(font
				(size 1.27 1.27)
			)
			(justify left bottom)
		)
	)
	(label "PMOD_A_8"
		(at 96.52 33.02 0)
		(effects
			(font
				(size 1.27 1.27)
			)
			(justify left bottom)
		)
	)
	(label "USER_IO.A29"
		(at 248.92 195.58 0)
		(effects
			(font
				(size 1.27 1.27)
			)
			(justify left bottom)
		)
	)
	(label "PMOD_B_1"
		(at 116.84 87.63 0)
		(effects
			(font
				(size 1.27 1.27)
			)
			(justify left bottom)
		)
	)
	(label "CW_HEADER.TSCK"
		(at 248.92 43.18 0)
		(effects
			(font
				(size 1.27 1.27)
			)
			(justify left bottom)
		)
	)
	(label "CW_HEADER.RST"
		(at 248.92 35.56 0)
		(effects
			(font
				(size 1.27 1.27)
			)
			(justify left bottom)
		)
	)
	(label "USER_IO.B17"
		(at 337.82 180.34 0)
		(effects
			(font
				(size 1.27 1.27)
			)
			(justify left bottom)
		)
	)
	(label "USER_IO.B19"
		(at 337.82 182.88 0)
		(effects
			(font
				(size 1.27 1.27)
			)
			(justify left bottom)
		)
	)
	(label "USER_IO.B24"
		(at 367.03 187.96 0)
		(effects
			(font
				(size 1.27 1.27)
			)
			(justify left bottom)
		)
	)
	(label "PMOD_A_10"
		(at 96.52 38.1 0)
		(effects
			(font
				(size 1.27 1.27)
			)
			(justify left bottom)
		)
	)
	(label "PMOD_A.IO9"
		(at 63.5 35.56 0)
		(effects
			(font
				(size 1.27 1.27)
			)
			(justify left bottom)
		)
	)
	(label "CW_HEADER.IO2"
		(at 364.49 43.18 0)
		(effects
			(font
				(size 1.27 1.27)
			)
			(justify left bottom)
		)
	)
	(label "USER_IO.BUTTON3"
		(at 336.55 110.49 0)
		(effects
			(font
				(size 1.27 1.27)
			)
			(justify left bottom)
		)
	)
	(label "USER_IO.DIP_SW2"
		(at 256.54 262.89 0)
		(effects
			(font
				(size 1.27 1.27)
			)
			(justify left bottom)
		)
	)
	(label "USER_IO.B3"
		(at 337.82 162.56 0)
		(effects
			(font
				(size 1.27 1.27)
			)
			(justify left bottom)
		)
	)
	(label "USER_IO.A17"
		(at 248.92 180.34 0)
		(effects
			(font
				(size 1.27 1.27)
			)
			(justify left bottom)
		)
	)
	(label "PMOD_A_3"
		(at 116.84 35.56 0)
		(effects
			(font
				(size 1.27 1.27)
			)
			(justify left bottom)
		)
	)
	(label "USER_IO.LED_GREEN5"
		(at 128.27 182.88 0)
		(effects
			(font
				(size 1.27 1.27)
			)
			(justify left bottom)
		)
	)
	(label "PMOD_A_4"
		(at 116.84 38.1 0)
		(effects
			(font
				(size 1.27 1.27)
			)
			(justify left bottom)
		)
	)
	(label "USER_IO.B31"
		(at 337.82 198.12 0)
		(effects
			(font
				(size 1.27 1.27)
			)
			(justify left bottom)
		)
	)
	(label "USER_IO.DIP_SW5"
		(at 292.1 232.41 0)
		(effects
			(font
				(size 1.27 1.27)
			)
			(justify left bottom)
		)
	)
	(label "PMOD_B.IO9"
		(at 63.5 92.71 0)
		(effects
			(font
				(size 1.27 1.27)
			)
			(justify left bottom)
		)
	)
	(label "CW_20PIN_IO2"
		(at 327.66 43.18 0)
		(effects
			(font
				(size 1.27 1.27)
			)
			(justify left bottom)
		)
	)
	(label "USER_IO.BUTTON2"
		(at 336.55 91.44 0)
		(effects
			(font
				(size 1.27 1.27)
			)
			(justify left bottom)
		)
	)
	(label "USER_IO.B23"
		(at 337.82 187.96 0)
		(effects
			(font
				(size 1.27 1.27)
			)
			(justify left bottom)
		)
	)
	(label "CW_HEADER.MOSI"
		(at 248.92 40.64 0)
		(effects
			(font
				(size 1.27 1.27)
			)
			(justify left bottom)
		)
	)
	(label "USER_IO.DIP_SW7"
		(at 292.1 237.49 0)
		(effects
			(font
				(size 1.27 1.27)
			)
			(justify left bottom)
		)
	)
	(label "USER_IO.DIP_SW7"
		(at 236.22 275.59 0)
		(effects
			(font
				(size 1.27 1.27)
			)
			(justify left bottom)
		)
	)
	(label "PMOD_A.IO7"
		(at 63.5 30.48 0)
		(effects
			(font
				(size 1.27 1.27)
			)
			(justify left bottom)
		)
	)
	(label "USER_IO.A24"
		(at 278.13 187.96 0)
		(effects
			(font
				(size 1.27 1.27)
			)
			(justify left bottom)
		)
	)
	(label "USER_IO.DIP_SW1"
		(at 256.54 260.35 0)
		(effects
			(font
				(size 1.27 1.27)
			)
			(justify left bottom)
		)
	)
	(label "USER_IO.A30"
		(at 278.13 195.58 0)
		(effects
			(font
				(size 1.27 1.27)
			)
			(justify left bottom)
		)
	)
	(label "USER_IO.A37"
		(at 248.92 205.74 0)
		(effects
			(font
				(size 1.27 1.27)
			)
			(justify left bottom)
		)
	)
	(label "USER_IO.A1"
		(at 248.92 160.02 0)
		(effects
			(font
				(size 1.27 1.27)
			)
			(justify left bottom)
		)
	)
	(label "USER_IO.LED_GREEN1"
		(at 45.72 182.88 0)
		(effects
			(font
				(size 1.27 1.27)
			)
			(justify left bottom)
		)
	)
	(label "USER_IO.A9"
		(at 248.92 170.18 0)
		(effects
			(font
				(size 1.27 1.27)
			)
			(justify left bottom)
		)
	)
	(label "USER_IO.BUTTON0"
		(at 261.62 91.44 0)
		(effects
			(font
				(size 1.27 1.27)
			)
			(justify left bottom)
		)
	)
	(label "USER_IO.B28"
		(at 367.03 193.04 0)
		(effects
			(font
				(size 1.27 1.27)
			)
			(justify left bottom)
		)
	)
	(label "USER_IO.LED_GREEN3"
		(at 45.72 219.71 0)
		(effects
			(font
				(size 1.27 1.27)
			)
			(justify left bottom)
		)
	)
	(label "CW_HEADER.TPDID"
		(at 248.92 48.26 0)
		(effects
			(font
				(size 1.27 1.27)
			)
			(justify left bottom)
		)
	)
	(label "CW_HEADER.IO3"
		(at 364.49 45.72 0)
		(effects
			(font
				(size 1.27 1.27)
			)
			(justify left bottom)
		)
	)
	(label "USER_IO.LED_GREEN4"
		(at 128.27 163.83 0)
		(effects
			(font
				(size 1.27 1.27)
			)
			(justify left bottom)
		)
	)
	(label "CW_20PIN_HS2"
		(at 327.66 35.56 0)
		(effects
			(font
				(size 1.27 1.27)
			)
			(justify left bottom)
		)
	)
	(label "CW_20PIN_IO4"
		(at 327.66 48.26 0)
		(effects
			(font
				(size 1.27 1.27)
			)
			(justify left bottom)
		)
	)
	(label "USER_IO.A35"
		(at 248.92 203.2 0)
		(effects
			(font
				(size 1.27 1.27)
			)
			(justify left bottom)
		)
	)
	(label "PMOD_A_9"
		(at 96.52 35.56 0)
		(effects
			(font
				(size 1.27 1.27)
			)
			(justify left bottom)
		)
	)
	(label "USER_IO.DIP_SW0"
		(at 256.54 257.81 0)
		(effects
			(font
				(size 1.27 1.27)
			)
			(justify left bottom)
		)
	)
	(label "USER_IO.B30"
		(at 367.03 195.58 0)
		(effects
			(font
				(size 1.27 1.27)
			)
			(justify left bottom)
		)
	)
	(label "USER_IO.A13"
		(at 248.92 175.26 0)
		(effects
			(font
				(size 1.27 1.27)
			)
			(justify left bottom)
		)
	)
	(label "PMOD_B_8"
		(at 95.25 90.17 0)
		(effects
			(font
				(size 1.27 1.27)
			)
			(justify left bottom)
		)
	)
	(label "CW_HEADER.IO1"
		(at 364.49 40.64 0)
		(effects
			(font
				(size 1.27 1.27)
			)
			(justify left bottom)
		)
	)
	(label "USER_IO.A12"
		(at 278.13 172.72 0)
		(effects
			(font
				(size 1.27 1.27)
			)
			(justify left bottom)
		)
	)
	(label "USER_IO.DIP_SW5"
		(at 256.54 270.51 0)
		(effects
			(font
				(size 1.27 1.27)
			)
			(justify left bottom)
		)
	)
	(label "CW_20PIN_MISO"
		(at 288.29 38.1 0)
		(effects
			(font
				(size 1.27 1.27)
			)
			(justify left bottom)
		)
	)
	(label "USER_IO.A3"
		(at 248.92 162.56 0)
		(effects
			(font
				(size 1.27 1.27)
			)
			(justify left bottom)
		)
	)
	(label "USER_IO.B6"
		(at 367.03 165.1 0)
		(effects
			(font
				(size 1.27 1.27)
			)
			(justify left bottom)
		)
	)
	(label "USER_IO.B11"
		(at 337.82 172.72 0)
		(effects
			(font
				(size 1.27 1.27)
			)
			(justify left bottom)
		)
	)
	(label "USER_IO.A23"
		(at 248.92 187.96 0)
		(effects
			(font
				(size 1.27 1.27)
			)
			(justify left bottom)
		)
	)
	(label "USER_IO.BUTTON1"
		(at 261.62 110.49 0)
		(effects
			(font
				(size 1.27 1.27)
			)
			(justify left bottom)
		)
	)
	(label "PMOD_B.IO1"
		(at 149.86 87.63 0)
		(effects
			(font
				(size 1.27 1.27)
			)
			(justify left bottom)
		)
	)
	(label "USER_IO.A16"
		(at 278.13 177.8 0)
		(effects
			(font
				(size 1.27 1.27)
			)
			(justify left bottom)
		)
	)
	(label "PMOD_A_2"
		(at 116.84 33.02 0)
		(effects
			(font
				(size 1.27 1.27)
			)
			(justify left bottom)
		)
	)
	(label "USER_IO.B7"
		(at 337.82 167.64 0)
		(effects
			(font
				(size 1.27 1.27)
			)
			(justify left bottom)
		)
	)
	(label "PMOD_B.IO10"
		(at 63.5 95.25 0)
		(effects
			(font
				(size 1.27 1.27)
			)
			(justify left bottom)
		)
	)
	(label "PMOD_B.IO3"
		(at 149.86 92.71 0)
		(effects
			(font
				(size 1.27 1.27)
			)
			(justify left bottom)
		)
	)
	(label "CW_20PIN_HS1"
		(at 327.66 33.02 0)
		(effects
			(font
				(size 1.27 1.27)
			)
			(justify left bottom)
		)
	)
	(label "USER_IO.A28"
		(at 278.13 193.04 0)
		(effects
			(font
				(size 1.27 1.27)
			)
			(justify left bottom)
		)
	)
	(label "USER_IO.DIP_SW2"
		(at 236.22 262.89 0)
		(effects
			(font
				(size 1.27 1.27)
			)
			(justify left bottom)
		)
	)
	(label "CW_HEADER.HS1"
		(at 364.49 33.02 0)
		(effects
			(font
				(size 1.27 1.27)
			)
			(justify left bottom)
		)
	)
	(label "USER_IO.A38"
		(at 278.13 205.74 0)
		(effects
			(font
				(size 1.27 1.27)
			)
			(justify left bottom)
		)
	)
	(label "PMOD_B.IO2"
		(at 149.86 90.17 0)
		(effects
			(font
				(size 1.27 1.27)
			)
			(justify left bottom)
		)
	)
	(label "USER_IO.A18"
		(at 278.13 180.34 0)
		(effects
			(font
				(size 1.27 1.27)
			)
			(justify left bottom)
		)
	)
	(label "USER_IO.LED_BLUE"
		(at 128.27 219.71 0)
		(effects
			(font
				(size 1.27 1.27)
			)
			(justify left bottom)
		)
	)
	(label "USER_IO.A14"
		(at 278.13 175.26 0)
		(effects
			(font
				(size 1.27 1.27)
			)
			(justify left bottom)
		)
	)
	(label "USER_IO.DIP_SW6"
		(at 256.54 273.05 0)
		(effects
			(font
				(size 1.27 1.27)
			)
			(justify left bottom)
		)
	)
	(label "USER_IO.A11"
		(at 248.92 172.72 0)
		(effects
			(font
				(size 1.27 1.27)
			)
			(justify left bottom)
		)
	)
	(label "USER_IO.A33"
		(at 248.92 200.66 0)
		(effects
			(font
				(size 1.27 1.27)
			)
			(justify left bottom)
		)
	)
	(label "CW_HEADER.MISO"
		(at 248.92 38.1 0)
		(effects
			(font
				(size 1.27 1.27)
			)
			(justify left bottom)
		)
	)
	(label "CW_HEADER.TPDIC"
		(at 248.92 45.72 0)
		(effects
			(font
				(size 1.27 1.27)
			)
			(justify left bottom)
		)
	)
	(label "USER_IO.A32"
		(at 278.13 198.12 0)
		(effects
			(font
				(size 1.27 1.27)
			)
			(justify left bottom)
		)
	)
	(label "PMOD_B.IO4"
		(at 149.86 95.25 0)
		(effects
			(font
				(size 1.27 1.27)
			)
			(justify left bottom)
		)
	)
	(label "PMOD_A.IO4"
		(at 149.86 38.1 0)
		(effects
			(font
				(size 1.27 1.27)
			)
			(justify left bottom)
		)
	)
	(label "USER_IO.B14"
		(at 367.03 175.26 0)
		(effects
			(font
				(size 1.27 1.27)
			)
			(justify left bottom)
		)
	)
	(label "CW_20PIN_IO1"
		(at 327.66 40.64 0)
		(effects
			(font
				(size 1.27 1.27)
			)
			(justify left bottom)
		)
	)
	(label "USER_IO.DIP_SW4"
		(at 292.1 229.87 0)
		(effects
			(font
				(size 1.27 1.27)
			)
			(justify left bottom)
		)
	)
	(label "USER_IO.LED_RED"
		(at 128.27 201.93 0)
		(effects
			(font
				(size 1.27 1.27)
			)
			(justify left bottom)
		)
	)
	(label "USER_IO.B26"
		(at 367.03 190.5 0)
		(effects
			(font
				(size 1.27 1.27)
			)
			(justify left bottom)
		)
	)
	(label "CW_HEADER.IO4"
		(at 364.49 48.26 0)
		(effects
			(font
				(size 1.27 1.27)
			)
			(justify left bottom)
		)
	)
	(label "PMOD_A.IO3"
		(at 149.86 35.56 0)
		(effects
			(font
				(size 1.27 1.27)
			)
			(justify left bottom)
		)
	)
	(label "SUP_MCU.FAN_PWM"
		(at 54.61 273.05 180)
		(effects
			(font
				(size 1.27 1.27)
			)
			(justify right bottom)
		)
	)
	(label "USER_IO.B32"
		(at 367.03 198.12 0)
		(effects
			(font
				(size 1.27 1.27)
			)
			(justify left bottom)
		)
	)
	(label "USER_IO.B15"
		(at 337.82 177.8 0)
		(effects
			(font
				(size 1.27 1.27)
			)
			(justify left bottom)
		)
	)
	(label "CW_20PIN_RST"
		(at 288.29 35.56 0)
		(effects
			(font
				(size 1.27 1.27)
			)
			(justify left bottom)
		)
	)
	(label "CW_HEADER.HS2"
		(at 364.49 35.56 0)
		(effects
			(font
				(size 1.27 1.27)
			)
			(justify left bottom)
		)
	)
	(label "PMOD_B.IO8"
		(at 63.5 90.17 0)
		(effects
			(font
				(size 1.27 1.27)
			)
			(justify left bottom)
		)
	)
	(label "CW_20PIN_TPDIC"
		(at 288.29 45.72 0)
		(effects
			(font
				(size 1.27 1.27)
			)
			(justify left bottom)
		)
	)
	(label "PMOD_A.IO10"
		(at 63.5 38.1 0)
		(effects
			(font
				(size 1.27 1.27)
			)
			(justify left bottom)
		)
	)
	(label "PMOD_B_3"
		(at 116.84 92.71 0)
		(effects
			(font
				(size 1.27 1.27)
			)
			(justify left bottom)
		)
	)
	(label "USER_IO.B21"
		(at 337.82 185.42 0)
		(effects
			(font
				(size 1.27 1.27)
			)
			(justify left bottom)
		)
	)
	(label "USER_IO.DIP_SW2"
		(at 247.65 234.95 0)
		(effects
			(font
				(size 1.27 1.27)
			)
			(justify left bottom)
		)
	)
	(label "PMOD_B_9"
		(at 95.25 92.71 0)
		(effects
			(font
				(size 1.27 1.27)
			)
			(justify left bottom)
		)
	)
	(label "USER_IO.B18"
		(at 367.03 180.34 0)
		(effects
			(font
				(size 1.27 1.27)
			)
			(justify left bottom)
		)
	)
	(label "USER_IO.B16"
		(at 367.03 177.8 0)
		(effects
			(font
				(size 1.27 1.27)
			)
			(justify left bottom)
		)
	)
	(label "USER_IO.DIP_SW3"
		(at 236.22 265.43 0)
		(effects
			(font
				(size 1.27 1.27)
			)
			(justify left bottom)
		)
	)
	(label "USER_IO.B29"
		(at 337.82 195.58 0)
		(effects
			(font
				(size 1.27 1.27)
			)
			(justify left bottom)
		)
	)
	(label "USER_IO.LED_GREEN2"
		(at 45.72 201.93 0)
		(effects
			(font
				(size 1.27 1.27)
			)
			(justify left bottom)
		)
	)
	(label "USER_IO.A25"
		(at 248.92 190.5 0)
		(effects
			(font
				(size 1.27 1.27)
			)
			(justify left bottom)
		)
	)
	(label "FAN_PWM_PIN"
		(at 77.47 267.97 0)
		(effects
			(font
				(size 1.27 1.27)
			)
			(justify left bottom)
		)
	)
	(label "USER_IO.DIP_SW0"
		(at 236.22 257.81 0)
		(effects
			(font
				(size 1.27 1.27)
			)
			(justify left bottom)
		)
	)
	(label "USER_IO.B33"
		(at 337.82 200.66 0)
		(effects
			(font
				(size 1.27 1.27)
			)
			(justify left bottom)
		)
	)
	(label "PMOD_B_7"
		(at 95.25 87.63 0)
		(effects
			(font
				(size 1.27 1.27)
			)
			(justify left bottom)
		)
	)
	(label "USER_IO.B27"
		(at 337.82 193.04 0)
		(effects
			(font
				(size 1.27 1.27)
			)
			(justify left bottom)
		)
	)
	(label "USER_IO.A40"
		(at 278.13 208.28 0)
		(effects
			(font
				(size 1.27 1.27)
			)
			(justify left bottom)
		)
	)
	(label "CW_20PIN_MOSI"
		(at 288.29 40.64 0)
		(effects
			(font
				(size 1.27 1.27)
			)
			(justify left bottom)
		)
	)
	(label "USER_IO.A15"
		(at 248.92 177.8 0)
		(effects
			(font
				(size 1.27 1.27)
			)
			(justify left bottom)
		)
	)
	(label "USER_IO.B8"
		(at 367.03 167.64 0)
		(effects
			(font
				(size 1.27 1.27)
			)
			(justify left bottom)
		)
	)
	(label "USER_IO.A39"
		(at 248.92 208.28 0)
		(effects
			(font
				(size 1.27 1.27)
			)
			(justify left bottom)
		)
	)
	(label "USER_IO.A36"
		(at 278.13 203.2 0)
		(effects
			(font
				(size 1.27 1.27)
			)
			(justify left bottom)
		)
	)
	(label "USER_IO.DIP_SW1"
		(at 236.22 260.35 0)
		(effects
			(font
				(size 1.27 1.27)
			)
			(justify left bottom)
		)
	)
	(label "PMOD_B_2"
		(at 116.84 90.17 0)
		(effects
			(font
				(size 1.27 1.27)
			)
			(justify left bottom)
		)
	)
	(hierarchical_label "USER_IO{USER-IO}"
		(shape bidirectional)
		(at 250.19 74.93 180)
		(effects
			(font
				(size 1.27 1.27)
			)
			(justify right)
		)
	)
	(hierarchical_label "PMOD_A{PMOD}"
		(shape bidirectional)
		(at 52.07 26.67 180)
		(effects
			(font
				(size 1.27 1.27)
			)
			(justify right)
		)
	)
	(hierarchical_label "USER_IO{USER-IO}"
		(shape bidirectional)
		(at 323.85 149.86 180)
		(effects
			(font
				(size 1.27 1.27)
			)
			(justify right)
		)
	)
	(hierarchical_label "PMOD_B{PMOD}"
		(shape bidirectional)
		(at 53.34 83.82 180)
		(effects
			(font
				(size 1.27 1.27)
			)
			(justify right)
		)
	)
	(hierarchical_label "SUP_MCU{SUP-MCU}"
		(shape bidirectional)
		(at 34.29 273.05 180)
		(effects
			(font
				(size 1.27 1.27)
			)
			(justify right)
		)
	)
	(hierarchical_label "USER_IO{USER-IO}"
		(shape bidirectional)
		(at 234.95 149.86 180)
		(effects
			(font
				(size 1.27 1.27)
			)
			(justify right)
		)
	)
	(hierarchical_label "USER_IO{USER-IO}"
		(shape bidirectional)
		(at 34.29 142.24 180)
		(effects
			(font
				(size 1.27 1.27)
			)
			(justify right)
		)
	)
	(hierarchical_label "USER_IO{USER-IO}"
		(shape bidirectional)
		(at 236.22 248.92 180)
		(effects
			(font
				(size 1.27 1.27)
			)
			(justify right)
		)
	)
	(hierarchical_label "FAN_PWM_CTRL"
		(shape input)
		(at 46.99 280.67 180)
		(effects
			(font
				(size 1.27 1.27)
			)
			(justify right)
		)
	)
	(hierarchical_label "CW_HEADER{CW-20PIN}"
		(shape bidirectional)
		(at 242.57 25.4 180)
		(effects
			(font
				(size 1.27 1.27)
			)
			(justify right)
		)
	)
	(hierarchical_label "USER_IO{USER-IO}"
		(shape bidirectional)
		(at 270.51 245.11 0)
		(effects
			(font
				(size 1.27 1.27)
			)
			(justify left)
		)
	)
	(hierarchical_label "USER_IO{USER-IO}"
		(shape bidirectional)
		(at 316.23 248.92 0)
		(effects
			(font
				(size 1.27 1.27)
			)
			(justify left)
		)
	)
	(symbol
		(lib_id "antmicroResistors0402:R_1k_0402")
		(at 137.16 212.09 0)
		(unit 1)
		(exclude_from_sim no)
		(in_bom yes)
		(on_board yes)
		(dnp no)
		(property "Reference" "R131"
			(at 139.7 207.01 0)
			(effects
				(font
					(size 1.27 1.27)
				)
			)
		)
		(property "Value" "R_1k_0402"
			(at 157.48 224.79 0)
			(effects
				(font
					(size 1.27 1.27)
					(thickness 0.15)
				)
				(justify left bottom)
				(hide yes)
			)
		)
		(property "Footprint" "antmicro-footprints:R_0402_1005Metric"
			(at 157.48 227.33 0)
			(effects
				(font
					(size 1.27 1.27)
					(thickness 0.15)
				)
				(justify left bottom)
				(hide yes)
			)
		)
		(property "Datasheet" "https://www.bourns.com/docs/product-datasheets/cr.pdf"
			(at 157.48 229.87 0)
			(effects
				(font
					(size 1.27 1.27)
					(thickness 0.15)
				)
				(justify left bottom)
				(hide yes)
			)
		)
		(property "Description" ""
			(at 137.16 212.09 0)
			(effects
				(font
					(size 1.27 1.27)
				)
			)
		)
		(property "Manufacturer" "Bourns"
			(at 157.48 234.95 0)
			(effects
				(font
					(size 1.27 1.27)
					(thickness 0.15)
				)
				(justify left bottom)
				(hide yes)
			)
		)
		(property "MPN" "CR0402-FX-1001GLF"
			(at 157.48 232.41 0)
			(effects
				(font
					(size 1.27 1.27)
					(thickness 0.15)
				)
				(justify left bottom)
				(hide yes)
			)
		)
		(property "Val" "1k"
			(at 139.7 209.55 0)
			(effects
				(font
					(size 1.27 1.27)
					(thickness 0.15)
				)
			)
		)
		(property "License" "Apache-2.0"
			(at 157.48 237.49 0)
			(effects
				(font
					(size 1.27 1.27)
					(thickness 0.15)
				)
				(justify left bottom)
				(hide yes)
			)
		)
		(property "Author" "Antmicro"
			(at 157.48 240.03 0)
			(effects
				(font
					(size 1.27 1.27)
					(thickness 0.15)
				)
				(justify left bottom)
				(hide yes)
			)
		)
		(property "Tolerance" "1%"
			(at 157.48 222.25 0)
			(effects
				(font
					(size 1.27 1.27)
				)
				(justify left bottom)
				(hide yes)
			)
		)
		(pin "1"
		)
		(pin "2"
		)
		(instances
			(project "k410t-devboard"
				(path ""
					(reference "R131")
					(unit 1)
				)
			)
		)
	)
	(symbol
		(lib_id "antmicroResistors0402:R_10k_0402")
		(at 279.4 102.87 270)
		(unit 1)
		(exclude_from_sim no)
		(in_bom yes)
		(on_board yes)
		(dnp no)
		(fields_autoplaced yes)
		(property "Reference" "R141"
			(at 281.305 104.1399 90)
			(effects
				(font
					(size 1.27 1.27)
				)
				(justify left)
			)
		)
		(property "Value" "R_10k_0402"
			(at 266.7 123.19 0)
			(effects
				(font
					(size 1.27 1.27)
					(thickness 0.15)
				)
				(justify left bottom)
				(hide yes)
			)
		)
		(property "Footprint" "antmicro-footprints:R_0402_1005Metric"
			(at 264.16 123.19 0)
			(effects
				(font
					(size 1.27 1.27)
					(thickness 0.15)
				)
				(justify left bottom)
				(hide yes)
			)
		)
		(property "Datasheet" "https://www.bourns.com/docs/product-datasheets/cr.pdf"
			(at 261.62 123.19 0)
			(effects
				(font
					(size 1.27 1.27)
					(thickness 0.15)
				)
				(justify left bottom)
				(hide yes)
			)
		)
		(property "Description" ""
			(at 279.4 102.87 0)
			(effects
				(font
					(size 1.27 1.27)
				)
			)
		)
		(property "Manufacturer" "Bourns"
			(at 256.54 123.19 0)
			(effects
				(font
					(size 1.27 1.27)
					(thickness 0.15)
				)
				(justify left bottom)
				(hide yes)
			)
		)
		(property "MPN" "CR0402-FX-1002GLF"
			(at 259.08 123.19 0)
			(effects
				(font
					(size 1.27 1.27)
					(thickness 0.15)
				)
				(justify left bottom)
				(hide yes)
			)
		)
		(property "Val" "10k"
			(at 281.305 106.6799 90)
			(effects
				(font
					(size 1.27 1.27)
					(thickness 0.15)
				)
				(justify left)
			)
		)
		(property "License" "Apache-2.0"
			(at 254 123.19 0)
			(effects
				(font
					(size 1.27 1.27)
					(thickness 0.15)
				)
				(justify left bottom)
				(hide yes)
			)
		)
		(property "Author" "Antmicro"
			(at 251.46 123.19 0)
			(effects
				(font
					(size 1.27 1.27)
					(thickness 0.15)
				)
				(justify left bottom)
				(hide yes)
			)
		)
		(property "Tolerance" "1%"
			(at 269.24 123.19 0)
			(effects
				(font
					(size 1.27 1.27)
				)
				(justify left bottom)
				(hide yes)
			)
		)
		(pin "1"
		)
		(pin "2"
		)
		(instances
			(project "k410t-devboard"
				(path ""
					(reference "R141")
					(unit 1)
				)
			)
		)
	)
	(symbol
		(lib_id "antmicropower:+1V8")
		(at 354.33 100.965 0)
		(unit 1)
		(exclude_from_sim no)
		(in_bom yes)
		(on_board yes)
		(dnp no)
		(property "Reference" "#PWR0175"
			(at 354.33 104.775 0)
			(effects
				(font
					(size 1.27 1.27)
				)
				(hide yes)
			)
		)
		(property "Value" "+1V8"
			(at 354.33 97.409 0)
			(effects
				(font
					(size 1.27 1.27)
				)
			)
		)
		(property "Footprint" ""
			(at 369.57 108.585 0)
			(effects
				(font
					(size 1.27 1.27)
					(thickness 0.15)
				)
				(justify left bottom)
				(hide yes)
			)
		)
		(property "Datasheet" ""
			(at 369.57 111.125 0)
			(effects
				(font
					(size 1.27 1.27)
					(thickness 0.15)
				)
				(justify left bottom)
				(hide yes)
			)
		)
		(property "Description" ""
			(at 354.33 100.965 0)
			(effects
				(font
					(size 1.27 1.27)
				)
			)
		)
		(property "Author" "Antmicro"
			(at 369.57 108.585 0)
			(effects
				(font
					(size 1.27 1.27)
					(thickness 0.15)
				)
				(justify left bottom)
				(hide yes)
			)
		)
		(property "License" "Apache-2.0"
			(at 369.57 111.125 0)
			(effects
				(font
					(size 1.27 1.27)
					(thickness 0.15)
				)
				(justify left bottom)
				(hide yes)
			)
		)
		(pin "1"
		)
		(instances
			(project "k410t-devboard"
				(path ""
					(reference "#PWR0175")
					(unit 1)
				)
			)
		)
	)
	(symbol
		(lib_id "antmicropower:GND")
		(at 262.89 241.3 0)
		(mirror y)
		(unit 1)
		(exclude_from_sim no)
		(in_bom yes)
		(on_board yes)
		(dnp no)
		(property "Reference" "#PWR0182"
			(at 262.89 247.65 0)
			(effects
				(font
					(size 1.27 1.27)
				)
				(hide yes)
			)
		)
		(property "Value" "GND"
			(at 262.89 245.11 0)
			(effects
				(font
					(size 1.27 1.27)
				)
			)
		)
		(property "Footprint" ""
			(at 254 248.92 0)
			(effects
				(font
					(size 1.27 1.27)
					(thickness 0.15)
				)
				(justify left bottom)
				(hide yes)
			)
		)
		(property "Datasheet" ""
			(at 254 254 0)
			(effects
				(font
					(size 1.27 1.27)
					(thickness 0.15)
				)
				(justify left bottom)
				(hide yes)
			)
		)
		(property "Description" ""
			(at 262.89 241.3 0)
			(effects
				(font
					(size 1.27 1.27)
				)
			)
		)
		(property "Author" "Antmicro"
			(at 254 248.92 0)
			(effects
				(font
					(size 1.27 1.27)
					(thickness 0.15)
				)
				(justify left bottom)
				(hide yes)
			)
		)
		(property "License" "Apache-2.0"
			(at 254 251.46 0)
			(effects
				(font
					(size 1.27 1.27)
					(thickness 0.15)
				)
				(justify left bottom)
				(hide yes)
			)
		)
		(pin "1"
		)
		(instances
			(project "k410t-devboard"
				(path ""
					(reference "#PWR0182")
					(unit 1)
				)
			)
		)
	)
	(symbol
		(lib_id "antmicropower:GND")
		(at 170.18 251.46 0)
		(unit 1)
		(exclude_from_sim no)
		(in_bom yes)
		(on_board yes)
		(dnp no)
		(fields_autoplaced yes)
		(property "Reference" "#PWR0168"
			(at 170.18 257.81 0)
			(effects
				(font
					(size 1.27 1.27)
				)
				(hide yes)
			)
		)
		(property "Value" "GND"
			(at 170.18 255.905 0)
			(effects
				(font
					(size 1.27 1.27)
				)
			)
		)
		(property "Footprint" ""
			(at 179.07 259.08 0)
			(effects
				(font
					(size 1.27 1.27)
					(thickness 0.15)
				)
				(justify left bottom)
				(hide yes)
			)
		)
		(property "Datasheet" ""
			(at 179.07 264.16 0)
			(effects
				(font
					(size 1.27 1.27)
					(thickness 0.15)
				)
				(justify left bottom)
				(hide yes)
			)
		)
		(property "Description" ""
			(at 170.18 251.46 0)
			(effects
				(font
					(size 1.27 1.27)
				)
			)
		)
		(property "Author" "Antmicro"
			(at 179.07 259.08 0)
			(effects
				(font
					(size 1.27 1.27)
					(thickness 0.15)
				)
				(justify left bottom)
				(hide yes)
			)
		)
		(property "License" "Apache-2.0"
			(at 179.07 261.62 0)
			(effects
				(font
					(size 1.27 1.27)
					(thickness 0.15)
				)
				(justify left bottom)
				(hide yes)
			)
		)
		(pin "1"
		)
		(instances
			(project "k410t-devboard"
				(path ""
					(reference "#PWR0168")
					(unit 1)
				)
			)
		)
	)
	(symbol
		(lib_id "antmicropower:+3.3V")
		(at 370.84 185.42 0)
		(unit 1)
		(exclude_from_sim no)
		(in_bom yes)
		(on_board yes)
		(dnp no)
		(fields_autoplaced yes)
		(property "Reference" "#PWR0177"
			(at 370.84 189.23 0)
			(effects
				(font
					(size 1.27 1.27)
				)
				(hide yes)
			)
		)
		(property "Value" "+3V3"
			(at 370.84 181.864 0)
			(effects
				(font
					(size 1.27 1.27)
				)
			)
		)
		(property "Footprint" ""
			(at 370.84 185.42 0)
			(effects
				(font
					(size 1.27 1.27)
				)
				(hide yes)
			)
		)
		(property "Datasheet" ""
			(at 370.84 185.42 0)
			(effects
				(font
					(size 1.27 1.27)
				)
				(hide yes)
			)
		)
		(property "Description" ""
			(at 370.84 185.42 0)
			(effects
				(font
					(size 1.27 1.27)
				)
			)
		)
		(pin "1"
		)
		(instances
			(project "k410t-devboard"
				(path ""
					(reference "#PWR0177")
					(unit 1)
				)
			)
		)
	)
	(symbol
		(lib_id "antmicroResistors0402:R_1k_0402")
		(at 137.16 173.99 0)
		(unit 1)
		(exclude_from_sim no)
		(in_bom yes)
		(on_board yes)
		(dnp no)
		(property "Reference" "R129"
			(at 139.7 168.91 0)
			(effects
				(font
					(size 1.27 1.27)
				)
			)
		)
		(property "Value" "R_1k_0402"
			(at 157.48 186.69 0)
			(effects
				(font
					(size 1.27 1.27)
					(thickness 0.15)
				)
				(justify left bottom)
				(hide yes)
			)
		)
		(property "Footprint" "antmicro-footprints:R_0402_1005Metric"
			(at 157.48 189.23 0)
			(effects
				(font
					(size 1.27 1.27)
					(thickness 0.15)
				)
				(justify left bottom)
				(hide yes)
			)
		)
		(property "Datasheet" "https://www.bourns.com/docs/product-datasheets/cr.pdf"
			(at 157.48 191.77 0)
			(effects
				(font
					(size 1.27 1.27)
					(thickness 0.15)
				)
				(justify left bottom)
				(hide yes)
			)
		)
		(property "Description" ""
			(at 137.16 173.99 0)
			(effects
				(font
					(size 1.27 1.27)
				)
			)
		)
		(property "Manufacturer" "Bourns"
			(at 157.48 196.85 0)
			(effects
				(font
					(size 1.27 1.27)
					(thickness 0.15)
				)
				(justify left bottom)
				(hide yes)
			)
		)
		(property "MPN" "CR0402-FX-1001GLF"
			(at 157.48 194.31 0)
			(effects
				(font
					(size 1.27 1.27)
					(thickness 0.15)
				)
				(justify left bottom)
				(hide yes)
			)
		)
		(property "Val" "1k"
			(at 139.7 171.45 0)
			(effects
				(font
					(size 1.27 1.27)
					(thickness 0.15)
				)
			)
		)
		(property "License" "Apache-2.0"
			(at 157.48 199.39 0)
			(effects
				(font
					(size 1.27 1.27)
					(thickness 0.15)
				)
				(justify left bottom)
				(hide yes)
			)
		)
		(property "Author" "Antmicro"
			(at 157.48 201.93 0)
			(effects
				(font
					(size 1.27 1.27)
					(thickness 0.15)
				)
				(justify left bottom)
				(hide yes)
			)
		)
		(property "Tolerance" "1%"
			(at 157.48 184.15 0)
			(effects
				(font
					(size 1.27 1.27)
				)
				(justify left bottom)
				(hide yes)
			)
		)
		(pin "1"
		)
		(pin "2"
		)
		(instances
			(project "k410t-devboard"
				(path ""
					(reference "R129")
					(unit 1)
				)
			)
		)
	)
	(symbol
		(lib_id "antmicroLEDIndicationDiscrete:LED_G_0603_KP-1608CGCK")
		(at 76.2 154.94 0)
		(mirror y)
		(unit 1)
		(exclude_from_sim no)
		(in_bom yes)
		(on_board yes)
		(dnp no)
		(property "Reference" "D18"
			(at 72.39 147.32 0)
			(effects
				(font
					(size 1.27 1.27)
				)
			)
		)
		(property "Value" "LED_G_0603_KP-1608CGCK"
			(at 72.39 158.115 0)
			(effects
				(font
					(size 1.27 1.27)
					(thickness 0.15)
				)
				(hide yes)
			)
		)
		(property "Footprint" "antmicro-footprints:LED_0603_1608Metric_G"
			(at 53.34 165.1 0)
			(effects
				(font
					(size 1.27 1.27)
					(thickness 0.15)
				)
				(justify left bottom)
				(hide yes)
			)
		)
		(property "Datasheet" "http://www.kingbright.com/attachments/file/psearch//000/00/00/KP-1608CGCK(Ver.23B).pdf"
			(at 53.34 167.64 0)
			(effects
				(font
					(size 1.27 1.27)
					(thickness 0.15)
				)
				(justify left bottom)
				(hide yes)
			)
		)
		(property "Description" ""
			(at 76.2 154.94 0)
			(effects
				(font
					(size 1.27 1.27)
				)
			)
		)
		(property "MPN" "KP-1608CGCK"
			(at 53.34 170.18 0)
			(effects
				(font
					(size 1.27 1.27)
					(thickness 0.15)
				)
				(justify left bottom)
				(hide yes)
			)
		)
		(property "Manufacturer" "Kingbright"
			(at 53.34 172.72 0)
			(effects
				(font
					(size 1.27 1.27)
					(thickness 0.15)
				)
				(justify left bottom)
				(hide yes)
			)
		)
		(property "Author" "Antmicro"
			(at 53.34 175.26 0)
			(effects
				(font
					(size 1.27 1.27)
					(thickness 0.15)
				)
				(justify left bottom)
				(hide yes)
			)
		)
		(property "License" "Apache-2.0"
			(at 53.34 177.8 0)
			(effects
				(font
					(size 1.27 1.27)
					(thickness 0.15)
				)
				(justify left bottom)
				(hide yes)
			)
		)
		(property "Color" "Green"
			(at 72.39 149.86 0)
			(effects
				(font
					(size 1.27 1.27)
				)
			)
		)
		(pin "1"
		)
		(pin "2"
		)
		(instances
			(project "k410t-devboard"
				(path ""
					(reference "D18")
					(unit 1)
				)
			)
		)
	)
	(symbol
		(lib_id "antmicroLEDIndicationDiscrete:LED_G_0603_KP-1608CGCK")
		(at 76.2 212.09 0)
		(mirror y)
		(unit 1)
		(exclude_from_sim no)
		(in_bom yes)
		(on_board yes)
		(dnp no)
		(property "Reference" "D21"
			(at 72.39 204.47 0)
			(effects
				(font
					(size 1.27 1.27)
				)
			)
		)
		(property "Value" "LED_G_0603_KP-1608CGCK"
			(at 72.39 215.265 0)
			(effects
				(font
					(size 1.27 1.27)
					(thickness 0.15)
				)
				(hide yes)
			)
		)
		(property "Footprint" "antmicro-footprints:LED_0603_1608Metric_G"
			(at 53.34 222.25 0)
			(effects
				(font
					(size 1.27 1.27)
					(thickness 0.15)
				)
				(justify left bottom)
				(hide yes)
			)
		)
		(property "Datasheet" "http://www.kingbright.com/attachments/file/psearch//000/00/00/KP-1608CGCK(Ver.23B).pdf"
			(at 53.34 224.79 0)
			(effects
				(font
					(size 1.27 1.27)
					(thickness 0.15)
				)
				(justify left bottom)
				(hide yes)
			)
		)
		(property "Description" ""
			(at 76.2 212.09 0)
			(effects
				(font
					(size 1.27 1.27)
				)
			)
		)
		(property "MPN" "KP-1608CGCK"
			(at 53.34 227.33 0)
			(effects
				(font
					(size 1.27 1.27)
					(thickness 0.15)
				)
				(justify left bottom)
				(hide yes)
			)
		)
		(property "Manufacturer" "Kingbright"
			(at 53.34 229.87 0)
			(effects
				(font
					(size 1.27 1.27)
					(thickness 0.15)
				)
				(justify left bottom)
				(hide yes)
			)
		)
		(property "Author" "Antmicro"
			(at 53.34 232.41 0)
			(effects
				(font
					(size 1.27 1.27)
					(thickness 0.15)
				)
				(justify left bottom)
				(hide yes)
			)
		)
		(property "License" "Apache-2.0"
			(at 53.34 234.95 0)
			(effects
				(font
					(size 1.27 1.27)
					(thickness 0.15)
				)
				(justify left bottom)
				(hide yes)
			)
		)
		(property "Color" "Green"
			(at 72.39 207.01 0)
			(effects
				(font
					(size 1.27 1.27)
				)
			)
		)
		(pin "1"
		)
		(pin "2"
		)
		(instances
			(project "k410t-devboard"
				(path ""
					(reference "D21")
					(unit 1)
				)
			)
		)
	)
	(symbol
		(lib_id "antmicroPushbuttonSwitches:SW_KMR211NGLFS_SMD")
		(at 387.35 91.44 0)
		(unit 1)
		(exclude_from_sim no)
		(in_bom yes)
		(on_board yes)
		(dnp no)
		(fields_autoplaced yes)
		(property "Reference" "S4"
			(at 392.43 83.82 0)
			(effects
				(font
					(size 1.27 1.27)
				)
			)
		)
		(property "Value" "SW_KMR211NGLFS_SMD"
			(at 392.43 95.885 0)
			(effects
				(font
					(size 1.27 1.27)
					(thickness 0.15)
				)
				(hide yes)
			)
		)
		(property "Footprint" "antmicro-footprints:SW_KMR211NGLFS_SMD"
			(at 412.75 99.06 0)
			(effects
				(font
					(size 1.27 1.27)
					(thickness 0.15)
				)
				(justify left bottom)
				(hide yes)
			)
		)
		(property "Datasheet" "http://www.farnell.com/datasheets/2631211.pdf"
			(at 412.75 101.6 0)
			(effects
				(font
					(size 1.27 1.27)
					(thickness 0.15)
				)
				(justify left bottom)
				(hide yes)
			)
		)
		(property "Description" ""
			(at 387.35 91.44 0)
			(effects
				(font
					(size 1.27 1.27)
				)
			)
		)
		(property "MPN" "KMR211NGLFS"
			(at 392.43 86.36 0)
			(effects
				(font
					(size 1.27 1.27)
					(thickness 0.15)
				)
			)
		)
		(property "Manufacturer" "C&K"
			(at 412.75 106.68 0)
			(effects
				(font
					(size 1.27 1.27)
					(thickness 0.15)
				)
				(justify left bottom)
				(hide yes)
			)
		)
		(property "Author" "Antmicro"
			(at 412.75 109.22 0)
			(effects
				(font
					(size 1.27 1.27)
					(thickness 0.15)
				)
				(justify left bottom)
				(hide yes)
			)
		)
		(property "License" "Apache-2.0"
			(at 412.75 111.76 0)
			(effects
				(font
					(size 1.27 1.27)
					(thickness 0.15)
				)
				(justify left bottom)
				(hide yes)
			)
		)
		(pin "1"
		)
		(pin "2"
		)
		(pin "3"
		)
		(pin "4"
		)
		(instances
			(project "k410t-devboard"
				(path ""
					(reference "S4")
					(unit 1)
				)
			)
		)
	)
	(symbol
		(lib_id "antmicroResistors0402:R_0R_0402")
		(at 57.15 280.67 0)
		(unit 1)
		(exclude_from_sim no)
		(in_bom yes)
		(on_board yes)
		(dnp no)
		(property "Reference" "R105"
			(at 64.77 279.4 0)
			(effects
				(font
					(size 1.27 1.27)
				)
			)
		)
		(property "Value" "R_0R_0402"
			(at 77.47 293.37 0)
			(effects
				(font
					(size 1.27 1.27)
					(thickness 0.15)
				)
				(justify left bottom)
				(hide yes)
			)
		)
		(property "Footprint" "antmicro-footprints:R_0402_1005Metric"
			(at 77.47 295.91 0)
			(effects
				(font
					(size 1.27 1.27)
					(thickness 0.15)
				)
				(justify left bottom)
				(hide yes)
			)
		)
		(property "Datasheet" "https://industrial.panasonic.com/cdbs/www-data/pdf/RDA0000/AOA0000C301.pdf"
			(at 77.47 298.45 0)
			(effects
				(font
					(size 1.27 1.27)
					(thickness 0.15)
				)
				(justify left bottom)
				(hide yes)
			)
		)
		(property "Description" ""
			(at 57.15 280.67 0)
			(effects
				(font
					(size 1.27 1.27)
				)
			)
		)
		(property "Manufacturer" "Panasonic"
			(at 77.47 303.53 0)
			(effects
				(font
					(size 1.27 1.27)
					(thickness 0.15)
				)
				(justify left bottom)
				(hide yes)
			)
		)
		(property "MPN" "ERJ2GE0R00X"
			(at 77.47 300.99 0)
			(effects
				(font
					(size 1.27 1.27)
					(thickness 0.15)
				)
				(justify left bottom)
				(hide yes)
			)
		)
		(property "Val" "0R"
			(at 55.88 279.4 0)
			(effects
				(font
					(size 1.27 1.27)
					(thickness 0.15)
				)
			)
		)
		(property "License" "Apache-2.0"
			(at 77.47 306.07 0)
			(effects
				(font
					(size 1.27 1.27)
					(thickness 0.15)
				)
				(justify left bottom)
				(hide yes)
			)
		)
		(property "Author" "Antmicro"
			(at 77.47 308.61 0)
			(effects
				(font
					(size 1.27 1.27)
					(thickness 0.15)
				)
				(justify left bottom)
				(hide yes)
			)
		)
		(property "Tolerance" "~"
			(at 77.47 290.83 0)
			(effects
				(font
					(size 1.27 1.27)
				)
				(justify left bottom)
				(hide yes)
			)
		)
		(property "Current" "1A"
			(at 59.69 288.925 0)
			(effects
				(font
					(size 1.27 1.27)
					(thickness 0.15)
				)
				(hide yes)
			)
		)
		(pin "1"
		)
		(pin "2"
		)
		(instances
			(project "k410t-devboard"
				(path ""
					(reference "R105")
					(unit 1)
				)
			)
		)
	)
	(symbol
		(lib_id "antmicroGenericPinHeaders:PinHeader_2x10_P1.27mm_SMD_Shrouded")
		(at 307.34 30.48 0)
		(unit 1)
		(exclude_from_sim no)
		(in_bom yes)
		(on_board yes)
		(dnp no)
		(property "Reference" "J10"
			(at 312.42 21.59 0)
			(effects
				(font
					(size 1.27 1.27)
				)
			)
		)
		(property "Value" "PinHeader_2x10_P1.27mm_SMD_Shrouded"
			(at 312.42 24.13 0)
			(effects
				(font
					(size 1.27 1.27)
					(thickness 0.15)
				)
			)
		)
		(property "Footprint" "antmicro-footprints:PinHeader_2x10_P1.27mm_SMD_Shrouded"
			(at 325.755 38.735 0)
			(effects
				(font
					(size 1.27 1.27)
					(thickness 0.15)
				)
				(justify left bottom)
				(hide yes)
			)
		)
		(property "Datasheet" "https://www.we-online.com/catalog/datasheet/62732020621.pdf"
			(at 325.755 41.275 0)
			(effects
				(font
					(size 1.27 1.27)
					(thickness 0.15)
				)
				(justify left bottom)
				(hide yes)
			)
		)
		(property "Description" ""
			(at 307.34 30.48 0)
			(effects
				(font
					(size 1.27 1.27)
				)
			)
		)
		(property "MPN" "62732020621"
			(at 325.755 43.815 0)
			(effects
				(font
					(size 1.27 1.27)
					(thickness 0.15)
				)
				(justify left bottom)
				(hide yes)
			)
		)
		(property "Manufacturer" "Würth Elektronik"
			(at 325.755 46.355 0)
			(effects
				(font
					(size 1.27 1.27)
					(thickness 0.15)
				)
				(justify left bottom)
				(hide yes)
			)
		)
		(property "Author" "Antmicro"
			(at 325.755 48.895 0)
			(effects
				(font
					(size 1.27 1.27)
					(thickness 0.15)
				)
				(justify left bottom)
				(hide yes)
			)
		)
		(property "License" "Apache-2.0"
			(at 325.755 51.435 0)
			(effects
				(font
					(size 1.27 1.27)
					(thickness 0.15)
				)
				(justify left bottom)
				(hide yes)
			)
		)
		(pin "1"
		)
		(pin "10"
		)
		(pin "11"
		)
		(pin "12"
		)
		(pin "13"
		)
		(pin "14"
		)
		(pin "15"
		)
		(pin "16"
		)
		(pin "17"
		)
		(pin "18"
		)
		(pin "19"
		)
		(pin "2"
		)
		(pin "20"
		)
		(pin "3"
		)
		(pin "4"
		)
		(pin "5"
		)
		(pin "6"
		)
		(pin "7"
		)
		(pin "8"
		)
		(pin "9"
		)
		(instances
			(project "k410t-devboard"
				(path ""
					(reference "J10")
					(unit 1)
				)
			)
		)
	)
	(symbol
		(lib_id "antmicroTVSDiodes:ESDA25P35-1U1M")
		(at 302.26 92.71 270)
		(unit 1)
		(exclude_from_sim no)
		(in_bom yes)
		(on_board yes)
		(dnp no)
		(property "Reference" "D35"
			(at 299.72 96.8375 90)
			(effects
				(font
					(size 1.27 1.27)
				)
				(justify right)
			)
		)
		(property "Value" "ESDA25P35-1U1M"
			(at 299.72 94.2976 90)
			(effects
				(font
					(size 1.27 1.27)
					(thickness 0.15)
				)
				(justify right)
				(hide yes)
			)
		)
		(property "Footprint" "antmicro-footprints:QFN-2L_1.6x1x0.55mm"
			(at 292.1 116.84 0)
			(effects
				(font
					(size 1.27 1.27)
					(thickness 0.15)
				)
				(justify left bottom)
				(hide yes)
			)
		)
		(property "Datasheet" "https://www.st.com/resource/en/datasheet/esda25p35-1u1m.pdf"
			(at 289.56 116.84 0)
			(effects
				(font
					(size 1.27 1.27)
					(thickness 0.15)
				)
				(justify left bottom)
				(hide yes)
			)
		)
		(property "Description" ""
			(at 302.26 92.71 0)
			(effects
				(font
					(size 1.27 1.27)
				)
			)
		)
		(property "MPN" "ESDA25P35-1U1M"
			(at 299.72 94.2975 90)
			(effects
				(font
					(size 1.27 1.27)
					(thickness 0.15)
				)
				(justify right)
			)
		)
		(property "Manufacturer" "STMicroelectronics"
			(at 284.48 116.84 0)
			(effects
				(font
					(size 1.27 1.27)
					(thickness 0.15)
				)
				(justify left bottom)
				(hide yes)
			)
		)
		(property "Author" "Antmicro"
			(at 281.94 116.84 0)
			(effects
				(font
					(size 1.27 1.27)
					(thickness 0.15)
				)
				(justify left bottom)
				(hide yes)
			)
		)
		(property "License" "Apache-2.0"
			(at 279.4 116.84 0)
			(effects
				(font
					(size 1.27 1.27)
					(thickness 0.15)
				)
				(justify left bottom)
				(hide yes)
			)
		)
		(property "Public" "False"
			(at 284.48 113.03 0)
			(effects
				(font
					(size 1.27 1.27)
				)
				(justify left bottom)
				(hide yes)
			)
		)
		(pin "1"
		)
		(pin "2"
		)
		(instances
			(project "k410t-devboard"
				(path ""
					(reference "D35")
					(unit 1)
				)
			)
		)
	)
	(symbol
		(lib_id "antmicroWire2BoardConnectors:JST_SH_1x4_BM04B-SRSS-TB-LF-SN")
		(at 139.7 250.19 0)
		(unit 1)
		(exclude_from_sim no)
		(in_bom yes)
		(on_board yes)
		(dnp no)
		(property "Reference" "J7"
			(at 140.97 245.11 0)
			(effects
				(font
					(size 1.27 1.27)
					(thickness 0.15)
				)
				(justify left)
			)
		)
		(property "Value" "JST_SH_1x4_BM04B-SRSS-TB-LF-SN"
			(at 160.02 257.81 0)
			(effects
				(font
					(size 1.27 1.27)
					(thickness 0.15)
				)
				(justify left bottom)
				(hide yes)
			)
		)
		(property "Footprint" "antmicro-footprints:Conn_JST_SH_1x4_BM04B-SRSS-TB-LF-SN"
			(at 160.02 260.35 0)
			(effects
				(font
					(size 1.27 1.27)
					(thickness 0.15)
				)
				(justify left bottom)
				(hide yes)
			)
		)
		(property "Datasheet" "https://www.jst-mfg.com/product/pdf/eng/eSH.pdf"
			(at 160.02 262.89 0)
			(effects
				(font
					(size 1.27 1.27)
					(thickness 0.15)
				)
				(justify left bottom)
				(hide yes)
			)
		)
		(property "Description" ""
			(at 139.7 250.19 0)
			(effects
				(font
					(size 1.27 1.27)
				)
			)
		)
		(property "MPN" "BM04B-SRSS-TB(LF)(SN) "
			(at 140.97 247.65 0)
			(effects
				(font
					(size 1.27 1.27)
					(thickness 0.15)
				)
				(justify left)
			)
		)
		(property "Manufacturer" "JST Automotive Connectors"
			(at 160.02 267.97 0)
			(effects
				(font
					(size 1.27 1.27)
					(thickness 0.15)
				)
				(justify left bottom)
				(hide yes)
			)
		)
		(property "Author" "Antmicro"
			(at 160.02 270.51 0)
			(effects
				(font
					(size 1.27 1.27)
					(thickness 0.15)
				)
				(justify left bottom)
				(hide yes)
			)
		)
		(property "License" "Apache-2.0"
			(at 160.02 273.05 0)
			(effects
				(font
					(size 1.27 1.27)
					(thickness 0.15)
				)
				(justify left bottom)
				(hide yes)
			)
		)
		(pin "1"
		)
		(pin "2"
		)
		(pin "3"
		)
		(pin "4"
		)
		(pin "MP"
		)
		(instances
			(project "k410t-devboard"
				(path ""
					(reference "J7")
					(unit 1)
				)
			)
		)
	)
	(symbol
		(lib_id "antmicroResistors0402:R_1k_0402")
		(at 54.61 212.09 0)
		(unit 1)
		(exclude_from_sim no)
		(in_bom yes)
		(on_board yes)
		(dnp no)
		(property "Reference" "R110"
			(at 57.15 207.01 0)
			(effects
				(font
					(size 1.27 1.27)
				)
			)
		)
		(property "Value" "R_1k_0402"
			(at 74.93 224.79 0)
			(effects
				(font
					(size 1.27 1.27)
					(thickness 0.15)
				)
				(justify left bottom)
				(hide yes)
			)
		)
		(property "Footprint" "antmicro-footprints:R_0402_1005Metric"
			(at 74.93 227.33 0)
			(effects
				(font
					(size 1.27 1.27)
					(thickness 0.15)
				)
				(justify left bottom)
				(hide yes)
			)
		)
		(property "Datasheet" "https://www.bourns.com/docs/product-datasheets/cr.pdf"
			(at 74.93 229.87 0)
			(effects
				(font
					(size 1.27 1.27)
					(thickness 0.15)
				)
				(justify left bottom)
				(hide yes)
			)
		)
		(property "Description" ""
			(at 54.61 212.09 0)
			(effects
				(font
					(size 1.27 1.27)
				)
			)
		)
		(property "Manufacturer" "Bourns"
			(at 74.93 234.95 0)
			(effects
				(font
					(size 1.27 1.27)
					(thickness 0.15)
				)
				(justify left bottom)
				(hide yes)
			)
		)
		(property "MPN" "CR0402-FX-1001GLF"
			(at 74.93 232.41 0)
			(effects
				(font
					(size 1.27 1.27)
					(thickness 0.15)
				)
				(justify left bottom)
				(hide yes)
			)
		)
		(property "Val" "1k"
			(at 57.15 209.55 0)
			(effects
				(font
					(size 1.27 1.27)
					(thickness 0.15)
				)
			)
		)
		(property "License" "Apache-2.0"
			(at 74.93 237.49 0)
			(effects
				(font
					(size 1.27 1.27)
					(thickness 0.15)
				)
				(justify left bottom)
				(hide yes)
			)
		)
		(property "Author" "Antmicro"
			(at 74.93 240.03 0)
			(effects
				(font
					(size 1.27 1.27)
					(thickness 0.15)
				)
				(justify left bottom)
				(hide yes)
			)
		)
		(property "Tolerance" "1%"
			(at 74.93 222.25 0)
			(effects
				(font
					(size 1.27 1.27)
				)
				(justify left bottom)
				(hide yes)
			)
		)
		(pin "1"
		)
		(pin "2"
		)
		(instances
			(project "k410t-devboard"
				(path ""
					(reference "R110")
					(unit 1)
				)
			)
		)
	)
	(symbol
		(lib_id "antmicroResistors0402:R_100k_0402")
		(at 107.95 219.71 0)
		(unit 1)
		(exclude_from_sim no)
		(in_bom yes)
		(on_board yes)
		(dnp no)
		(property "Reference" "R356"
			(at 110.49 214.63 0)
			(effects
				(font
					(size 1.27 1.27)
				)
			)
		)
		(property "Value" "R_100k_0402"
			(at 128.27 232.41 0)
			(effects
				(font
					(size 1.27 1.27)
					(thickness 0.15)
				)
				(justify left bottom)
				(hide yes)
			)
		)
		(property "Footprint" "antmicro-footprints:R_0402_1005Metric"
			(at 128.27 234.95 0)
			(effects
				(font
					(size 1.27 1.27)
					(thickness 0.15)
				)
				(justify left bottom)
				(hide yes)
			)
		)
		(property "Datasheet" "https://www.bourns.com/docs/product-datasheets/cr.pdf"
			(at 128.27 237.49 0)
			(effects
				(font
					(size 1.27 1.27)
					(thickness 0.15)
				)
				(justify left bottom)
				(hide yes)
			)
		)
		(property "Description" ""
			(at 107.95 219.71 0)
			(effects
				(font
					(size 1.27 1.27)
				)
			)
		)
		(property "Manufacturer" "Bourns"
			(at 128.27 242.57 0)
			(effects
				(font
					(size 1.27 1.27)
					(thickness 0.15)
				)
				(justify left bottom)
				(hide yes)
			)
		)
		(property "MPN" "CR0402-FX-1003GLF"
			(at 128.27 240.03 0)
			(effects
				(font
					(size 1.27 1.27)
					(thickness 0.15)
				)
				(justify left bottom)
				(hide yes)
			)
		)
		(property "Val" "100k"
			(at 110.49 217.17 0)
			(effects
				(font
					(size 1.27 1.27)
					(thickness 0.15)
				)
			)
		)
		(property "License" "Apache-2.0"
			(at 128.27 245.11 0)
			(effects
				(font
					(size 1.27 1.27)
					(thickness 0.15)
				)
				(justify left bottom)
				(hide yes)
			)
		)
		(property "Author" "Antmicro"
			(at 128.27 247.65 0)
			(effects
				(font
					(size 1.27 1.27)
					(thickness 0.15)
				)
				(justify left bottom)
				(hide yes)
			)
		)
		(property "Tolerance" "1%"
			(at 128.27 229.87 0)
			(effects
				(font
					(size 1.27 1.27)
				)
				(justify left bottom)
				(hide yes)
			)
		)
		(pin "1"
		)
		(pin "2"
		)
		(instances
			(project "k410t-devboard"
				(path ""
					(reference "R356")
					(unit 1)
				)
			)
		)
	)
	(symbol
		(lib_id "antmicroResistors0402:R_100R_0402")
		(at 140.97 90.17 180)
		(unit 1)
		(exclude_from_sim no)
		(in_bom yes)
		(on_board yes)
		(dnp no)
		(property "Reference" "R125"
			(at 143.51 88.9 0)
			(effects
				(font
					(size 1.27 1.27)
				)
			)
		)
		(property "Value" "R_100R_0402"
			(at 120.65 77.47 0)
			(effects
				(font
					(size 1.27 1.27)
					(thickness 0.15)
				)
				(justify left bottom)
				(hide yes)
			)
		)
		(property "Footprint" "antmicro-footprints:R_0402_1005Metric"
			(at 120.65 74.93 0)
			(effects
				(font
					(size 1.27 1.27)
					(thickness 0.15)
				)
				(justify left bottom)
				(hide yes)
			)
		)
		(property "Datasheet" "https://www.bourns.com/docs/product-datasheets/cr.pdf"
			(at 120.65 72.39 0)
			(effects
				(font
					(size 1.27 1.27)
					(thickness 0.15)
				)
				(justify left bottom)
				(hide yes)
			)
		)
		(property "Description" ""
			(at 140.97 90.17 0)
			(effects
				(font
					(size 1.27 1.27)
				)
			)
		)
		(property "Manufacturer" "Bourns"
			(at 120.65 67.31 0)
			(effects
				(font
					(size 1.27 1.27)
					(thickness 0.15)
				)
				(justify left bottom)
				(hide yes)
			)
		)
		(property "MPN" "CR0402-FX-1000GLF"
			(at 120.65 69.85 0)
			(effects
				(font
					(size 1.27 1.27)
					(thickness 0.15)
				)
				(justify left bottom)
				(hide yes)
			)
		)
		(property "Val" "100R"
			(at 133.35 88.9 0)
			(effects
				(font
					(size 1.27 1.27)
					(thickness 0.15)
				)
			)
		)
		(property "License" "Apache-2.0"
			(at 120.65 64.77 0)
			(effects
				(font
					(size 1.27 1.27)
					(thickness 0.15)
				)
				(justify left bottom)
				(hide yes)
			)
		)
		(property "Author" "Antmicro"
			(at 120.65 62.23 0)
			(effects
				(font
					(size 1.27 1.27)
					(thickness 0.15)
				)
				(justify left bottom)
				(hide yes)
			)
		)
		(property "Tolerance" "1%"
			(at 120.65 80.01 0)
			(effects
				(font
					(size 1.27 1.27)
				)
				(justify left bottom)
				(hide yes)
			)
		)
		(pin "1"
		)
		(pin "2"
		)
		(instances
			(project "k410t-devboard"
				(path ""
					(reference "R125")
					(unit 1)
				)
			)
		)
	)
	(symbol
		(lib_id "antmicroGenericPinHeaders:PinHeader_2x20_P1.27mm_SMD_Shrouded")
		(at 264.16 160.02 0)
		(unit 1)
		(exclude_from_sim no)
		(in_bom yes)
		(on_board yes)
		(dnp no)
		(property "Reference" "J9"
			(at 269.24 152.4 0)
			(effects
				(font
					(size 1.27 1.27)
				)
			)
		)
		(property "Value" "PinHeader_2x20_P1.27mm_SMD_Shrouded"
			(at 269.24 154.94 0)
			(effects
				(font
					(size 1.27 1.27)
					(thickness 0.15)
				)
			)
		)
		(property "Footprint" "antmicro-footprints:PinHeader_2x20_P1.27mm_SMD_Shrouded"
			(at 289.56 171.45 0)
			(effects
				(font
					(size 1.27 1.27)
					(thickness 0.15)
				)
				(justify left bottom)
				(hide yes)
			)
		)
		(property "Datasheet" "https://www.we-online.com/catalog/datasheet/62704020621.pdf"
			(at 289.56 173.99 0)
			(effects
				(font
					(size 1.27 1.27)
					(thickness 0.15)
				)
				(justify left bottom)
				(hide yes)
			)
		)
		(property "Description" ""
			(at 264.16 160.02 0)
			(effects
				(font
					(size 1.27 1.27)
				)
			)
		)
		(property "MPN" "62704020621"
			(at 289.56 176.53 0)
			(effects
				(font
					(size 1.27 1.27)
					(thickness 0.15)
				)
				(justify left bottom)
				(hide yes)
			)
		)
		(property "Manufacturer" "Würth Elektronik"
			(at 289.56 179.07 0)
			(effects
				(font
					(size 1.27 1.27)
					(thickness 0.15)
				)
				(justify left bottom)
				(hide yes)
			)
		)
		(property "Author" "Antmicro"
			(at 289.56 181.61 0)
			(effects
				(font
					(size 1.27 1.27)
					(thickness 0.15)
				)
				(justify left bottom)
				(hide yes)
			)
		)
		(property "License" "Apache-2.0"
			(at 289.56 184.15 0)
			(effects
				(font
					(size 1.27 1.27)
					(thickness 0.15)
				)
				(justify left bottom)
				(hide yes)
			)
		)
		(pin "1"
		)
		(pin "10"
		)
		(pin "11"
		)
		(pin "12"
		)
		(pin "13"
		)
		(pin "14"
		)
		(pin "15"
		)
		(pin "16"
		)
		(pin "17"
		)
		(pin "18"
		)
		(pin "19"
		)
		(pin "2"
		)
		(pin "20"
		)
		(pin "21"
		)
		(pin "22"
		)
		(pin "23"
		)
		(pin "24"
		)
		(pin "25"
		)
		(pin "26"
		)
		(pin "27"
		)
		(pin "28"
		)
		(pin "29"
		)
		(pin "3"
		)
		(pin "30"
		)
		(pin "31"
		)
		(pin "32"
		)
		(pin "33"
		)
		(pin "34"
		)
		(pin "35"
		)
		(pin "36"
		)
		(pin "37"
		)
		(pin "38"
		)
		(pin "39"
		)
		(pin "4"
		)
		(pin "40"
		)
		(pin "5"
		)
		(pin "6"
		)
		(pin "7"
		)
		(pin "8"
		)
		(pin "9"
		)
		(instances
			(project "k410t-devboard"
				(path ""
					(reference "J9")
					(unit 1)
				)
			)
		)
	)
	(symbol
		(lib_id "antmicroLEDIndicationDiscrete:LED_G_0603_KP-1608CGCK")
		(at 76.2 193.04 0)
		(mirror y)
		(unit 1)
		(exclude_from_sim no)
		(in_bom yes)
		(on_board yes)
		(dnp no)
		(property "Reference" "D20"
			(at 72.39 185.42 0)
			(effects
				(font
					(size 1.27 1.27)
				)
			)
		)
		(property "Value" "LED_G_0603_KP-1608CGCK"
			(at 72.39 196.215 0)
			(effects
				(font
					(size 1.27 1.27)
					(thickness 0.15)
				)
				(hide yes)
			)
		)
		(property "Footprint" "antmicro-footprints:LED_0603_1608Metric_G"
			(at 53.34 203.2 0)
			(effects
				(font
					(size 1.27 1.27)
					(thickness 0.15)
				)
				(justify left bottom)
				(hide yes)
			)
		)
		(property "Datasheet" "http://www.kingbright.com/attachments/file/psearch//000/00/00/KP-1608CGCK(Ver.23B).pdf"
			(at 53.34 205.74 0)
			(effects
				(font
					(size 1.27 1.27)
					(thickness 0.15)
				)
				(justify left bottom)
				(hide yes)
			)
		)
		(property "Description" ""
			(at 76.2 193.04 0)
			(effects
				(font
					(size 1.27 1.27)
				)
			)
		)
		(property "MPN" "KP-1608CGCK"
			(at 53.34 208.28 0)
			(effects
				(font
					(size 1.27 1.27)
					(thickness 0.15)
				)
				(justify left bottom)
				(hide yes)
			)
		)
		(property "Manufacturer" "Kingbright"
			(at 53.34 210.82 0)
			(effects
				(font
					(size 1.27 1.27)
					(thickness 0.15)
				)
				(justify left bottom)
				(hide yes)
			)
		)
		(property "Author" "Antmicro"
			(at 53.34 213.36 0)
			(effects
				(font
					(size 1.27 1.27)
					(thickness 0.15)
				)
				(justify left bottom)
				(hide yes)
			)
		)
		(property "License" "Apache-2.0"
			(at 53.34 215.9 0)
			(effects
				(font
					(size 1.27 1.27)
					(thickness 0.15)
				)
				(justify left bottom)
				(hide yes)
			)
		)
		(property "Color" "Green"
			(at 72.39 187.96 0)
			(effects
				(font
					(size 1.27 1.27)
				)
			)
		)
		(pin "1"
		)
		(pin "2"
		)
		(instances
			(project "k410t-devboard"
				(path ""
					(reference "D20")
					(unit 1)
				)
			)
		)
	)
	(symbol
		(lib_id "antmicroGenericPinSockets:PinSocket_2x6_P2.54mm_Drill1.04mm_Horizontal")
		(at 106.68 87.63 0)
		(unit 1)
		(exclude_from_sim no)
		(in_bom yes)
		(on_board yes)
		(dnp no)
		(fields_autoplaced yes)
		(property "Reference" "J6"
			(at 111.76 80.01 0)
			(effects
				(font
					(size 1.27 1.27)
				)
			)
		)
		(property "Value" "PinSocket_2x6_P2.54mm_Drill1.04mm_Horizontal"
			(at 111.76 81.915 0)
			(effects
				(font
					(size 1.27 1.27)
					(thickness 0.15)
				)
				(hide yes)
			)
		)
		(property "Footprint" "antmicro-footprints:PinSocket_2x6_P2.54mm_Drill1.04mm_Horizontal"
			(at 125.73 92.71 0)
			(effects
				(font
					(size 1.27 1.27)
					(thickness 0.15)
				)
				(justify left bottom)
				(hide yes)
			)
		)
		(property "Datasheet" "https://suddendocs.samtec.com/prints/ssw-1xx-xx-xxx-x-xx-xxx-xx-mkt.pdf"
			(at 125.73 95.25 0)
			(effects
				(font
					(size 1.27 1.27)
					(thickness 0.15)
				)
				(justify left bottom)
				(hide yes)
			)
		)
		(property "Description" ""
			(at 106.68 87.63 0)
			(effects
				(font
					(size 1.27 1.27)
				)
			)
		)
		(property "Manufacturer" "Samtec"
			(at 125.73 97.79 0)
			(effects
				(font
					(size 1.27 1.27)
					(thickness 0.15)
				)
				(justify left bottom)
				(hide yes)
			)
		)
		(property "MPN" "SSW-106-02-G-D-RA"
			(at 111.76 82.55 0)
			(effects
				(font
					(size 1.27 1.27)
					(thickness 0.15)
				)
			)
		)
		(property "Author" "Antmicro"
			(at 125.73 102.87 0)
			(effects
				(font
					(size 1.27 1.27)
					(thickness 0.15)
				)
				(justify left bottom)
				(hide yes)
			)
		)
		(property "License" "Apache-2.0"
			(at 125.73 105.41 0)
			(effects
				(font
					(size 1.27 1.27)
					(thickness 0.15)
				)
				(justify left bottom)
				(hide yes)
			)
		)
		(pin "1"
		)
		(pin "10"
		)
		(pin "11"
		)
		(pin "12"
		)
		(pin "2"
		)
		(pin "3"
		)
		(pin "4"
		)
		(pin "5"
		)
		(pin "6"
		)
		(pin "7"
		)
		(pin "8"
		)
		(pin "9"
		)
		(instances
			(project "k410t-devboard"
				(path ""
					(reference "J6")
					(unit 1)
				)
			)
		)
	)
	(symbol
		(lib_id "antmicroResistors0402:R_100R_0402")
		(at 87.63 33.02 180)
		(unit 1)
		(exclude_from_sim no)
		(in_bom yes)
		(on_board yes)
		(dnp no)
		(property "Reference" "R113"
			(at 90.17 31.75 0)
			(effects
				(font
					(size 1.27 1.27)
				)
			)
		)
		(property "Value" "R_100R_0402"
			(at 67.31 20.32 0)
			(effects
				(font
					(size 1.27 1.27)
					(thickness 0.15)
				)
				(justify left bottom)
				(hide yes)
			)
		)
		(property "Footprint" "antmicro-footprints:R_0402_1005Metric"
			(at 67.31 17.78 0)
			(effects
				(font
					(size 1.27 1.27)
					(thickness 0.15)
				)
				(justify left bottom)
				(hide yes)
			)
		)
		(property "Datasheet" "https://www.bourns.com/docs/product-datasheets/cr.pdf"
			(at 67.31 15.24 0)
			(effects
				(font
					(size 1.27 1.27)
					(thickness 0.15)
				)
				(justify left bottom)
				(hide yes)
			)
		)
		(property "Description" ""
			(at 87.63 33.02 0)
			(effects
				(font
					(size 1.27 1.27)
				)
			)
		)
		(property "Manufacturer" "Bourns"
			(at 67.31 10.16 0)
			(effects
				(font
					(size 1.27 1.27)
					(thickness 0.15)
				)
				(justify left bottom)
				(hide yes)
			)
		)
		(property "MPN" "CR0402-FX-1000GLF"
			(at 67.31 12.7 0)
			(effects
				(font
					(size 1.27 1.27)
					(thickness 0.15)
				)
				(justify left bottom)
				(hide yes)
			)
		)
		(property "Val" "100R"
			(at 80.01 31.75 0)
			(effects
				(font
					(size 1.27 1.27)
					(thickness 0.15)
				)
			)
		)
		(property "License" "Apache-2.0"
			(at 67.31 7.62 0)
			(effects
				(font
					(size 1.27 1.27)
					(thickness 0.15)
				)
				(justify left bottom)
				(hide yes)
			)
		)
		(property "Author" "Antmicro"
			(at 67.31 5.08 0)
			(effects
				(font
					(size 1.27 1.27)
					(thickness 0.15)
				)
				(justify left bottom)
				(hide yes)
			)
		)
		(property "Tolerance" "1%"
			(at 67.31 22.86 0)
			(effects
				(font
					(size 1.27 1.27)
				)
				(justify left bottom)
				(hide yes)
			)
		)
		(pin "1"
		)
		(pin "2"
		)
		(instances
			(project "k410t-devboard"
				(path ""
					(reference "R113")
					(unit 1)
				)
			)
		)
	)
	(symbol
		(lib_id "antmicropower:GND")
		(at 198.12 203.2 0)
		(unit 1)
		(exclude_from_sim no)
		(in_bom yes)
		(on_board yes)
		(dnp no)
		(property "Reference" "#PWR0180"
			(at 198.12 209.55 0)
			(effects
				(font
					(size 1.27 1.27)
				)
				(hide yes)
			)
		)
		(property "Value" "GND"
			(at 198.12 207.01 0)
			(effects
				(font
					(size 1.27 1.27)
				)
			)
		)
		(property "Footprint" ""
			(at 207.01 210.82 0)
			(effects
				(font
					(size 1.27 1.27)
					(thickness 0.15)
				)
				(justify left bottom)
				(hide yes)
			)
		)
		(property "Datasheet" ""
			(at 207.01 215.9 0)
			(effects
				(font
					(size 1.27 1.27)
					(thickness 0.15)
				)
				(justify left bottom)
				(hide yes)
			)
		)
		(property "Description" ""
			(at 198.12 203.2 0)
			(effects
				(font
					(size 1.27 1.27)
				)
			)
		)
		(property "Author" "Antmicro"
			(at 207.01 210.82 0)
			(effects
				(font
					(size 1.27 1.27)
					(thickness 0.15)
				)
				(justify left bottom)
				(hide yes)
			)
		)
		(property "License" "Apache-2.0"
			(at 207.01 213.36 0)
			(effects
				(font
					(size 1.27 1.27)
					(thickness 0.15)
				)
				(justify left bottom)
				(hide yes)
			)
		)
		(pin "1"
		)
		(instances
			(project "k410t-devboard"
				(path ""
					(reference "#PWR0180")
					(unit 1)
				)
			)
		)
	)
	(symbol
		(lib_id "antmicropower:GND")
		(at 104.14 175.26 0)
		(unit 1)
		(exclude_from_sim no)
		(in_bom yes)
		(on_board yes)
		(dnp no)
		(property "Reference" "#PWR0143"
			(at 104.14 181.61 0)
			(effects
				(font
					(size 1.27 1.27)
				)
				(hide yes)
			)
		)
		(property "Value" "GND"
			(at 104.14 179.07 0)
			(effects
				(font
					(size 1.27 1.27)
				)
			)
		)
		(property "Footprint" ""
			(at 113.03 182.88 0)
			(effects
				(font
					(size 1.27 1.27)
					(thickness 0.15)
				)
				(justify left bottom)
				(hide yes)
			)
		)
		(property "Datasheet" ""
			(at 113.03 187.96 0)
			(effects
				(font
					(size 1.27 1.27)
					(thickness 0.15)
				)
				(justify left bottom)
				(hide yes)
			)
		)
		(property "Description" ""
			(at 104.14 175.26 0)
			(effects
				(font
					(size 1.27 1.27)
				)
			)
		)
		(property "Author" "Antmicro"
			(at 113.03 182.88 0)
			(effects
				(font
					(size 1.27 1.27)
					(thickness 0.15)
				)
				(justify left bottom)
				(hide yes)
			)
		)
		(property "License" "Apache-2.0"
			(at 113.03 185.42 0)
			(effects
				(font
					(size 1.27 1.27)
					(thickness 0.15)
				)
				(justify left bottom)
				(hide yes)
			)
		)
		(pin "1"
		)
		(instances
			(project "k410t-devboard"
				(path ""
					(reference "#PWR0143")
					(unit 1)
				)
			)
		)
	)
	(symbol
		(lib_id "antmicroResistors0402:R_1k_0402")
		(at 137.16 154.94 0)
		(unit 1)
		(exclude_from_sim no)
		(in_bom yes)
		(on_board yes)
		(dnp no)
		(property "Reference" "R128"
			(at 139.7 149.86 0)
			(effects
				(font
					(size 1.27 1.27)
				)
			)
		)
		(property "Value" "R_1k_0402"
			(at 157.48 167.64 0)
			(effects
				(font
					(size 1.27 1.27)
					(thickness 0.15)
				)
				(justify left bottom)
				(hide yes)
			)
		)
		(property "Footprint" "antmicro-footprints:R_0402_1005Metric"
			(at 157.48 170.18 0)
			(effects
				(font
					(size 1.27 1.27)
					(thickness 0.15)
				)
				(justify left bottom)
				(hide yes)
			)
		)
		(property "Datasheet" "https://www.bourns.com/docs/product-datasheets/cr.pdf"
			(at 157.48 172.72 0)
			(effects
				(font
					(size 1.27 1.27)
					(thickness 0.15)
				)
				(justify left bottom)
				(hide yes)
			)
		)
		(property "Description" ""
			(at 137.16 154.94 0)
			(effects
				(font
					(size 1.27 1.27)
				)
			)
		)
		(property "Manufacturer" "Bourns"
			(at 157.48 177.8 0)
			(effects
				(font
					(size 1.27 1.27)
					(thickness 0.15)
				)
				(justify left bottom)
				(hide yes)
			)
		)
		(property "MPN" "CR0402-FX-1001GLF"
			(at 157.48 175.26 0)
			(effects
				(font
					(size 1.27 1.27)
					(thickness 0.15)
				)
				(justify left bottom)
				(hide yes)
			)
		)
		(property "Val" "1k"
			(at 139.7 152.4 0)
			(effects
				(font
					(size 1.27 1.27)
					(thickness 0.15)
				)
			)
		)
		(property "License" "Apache-2.0"
			(at 157.48 180.34 0)
			(effects
				(font
					(size 1.27 1.27)
					(thickness 0.15)
				)
				(justify left bottom)
				(hide yes)
			)
		)
		(property "Author" "Antmicro"
			(at 157.48 182.88 0)
			(effects
				(font
					(size 1.27 1.27)
					(thickness 0.15)
				)
				(justify left bottom)
				(hide yes)
			)
		)
		(property "Tolerance" "1%"
			(at 157.48 165.1 0)
			(effects
				(font
					(size 1.27 1.27)
				)
				(justify left bottom)
				(hide yes)
			)
		)
		(pin "1"
		)
		(pin "2"
		)
		(instances
			(project "k410t-devboard"
				(path ""
					(reference "R128")
					(unit 1)
				)
			)
		)
	)
	(symbol
		(lib_id "antmicropower:+3.3V")
		(at 49.53 170.18 0)
		(unit 1)
		(exclude_from_sim no)
		(in_bom yes)
		(on_board yes)
		(dnp no)
		(fields_autoplaced yes)
		(property "Reference" "#PWR0129"
			(at 49.53 173.99 0)
			(effects
				(font
					(size 1.27 1.27)
				)
				(hide yes)
			)
		)
		(property "Value" "+3V3"
			(at 49.53 166.624 0)
			(effects
				(font
					(size 1.27 1.27)
				)
			)
		)
		(property "Footprint" ""
			(at 49.53 170.18 0)
			(effects
				(font
					(size 1.27 1.27)
				)
				(hide yes)
			)
		)
		(property "Datasheet" ""
			(at 49.53 170.18 0)
			(effects
				(font
					(size 1.27 1.27)
				)
				(hide yes)
			)
		)
		(property "Description" ""
			(at 49.53 170.18 0)
			(effects
				(font
					(size 1.27 1.27)
				)
			)
		)
		(pin "1"
		)
		(instances
			(project "k410t-devboard"
				(path ""
					(reference "#PWR0129")
					(unit 1)
				)
			)
		)
	)
	(symbol
		(lib_id "antmicroCapacitors0402:C_1u_0402")
		(at 111.76 116.84 90)
		(unit 1)
		(exclude_from_sim no)
		(in_bom yes)
		(on_board yes)
		(dnp no)
		(property "Reference" "C215"
			(at 113.665 113.03 90)
			(effects
				(font
					(size 1.27 1.27)
				)
				(justify right)
			)
		)
		(property "Value" "C_1u_0402"
			(at 121.92 96.52 0)
			(effects
				(font
					(size 1.27 1.27)
					(thickness 0.15)
				)
				(justify left bottom)
				(hide yes)
			)
		)
		(property "Footprint" "antmicro-footprints:C_0402_1005Metric"
			(at 124.46 96.52 0)
			(effects
				(font
					(size 1.27 1.27)
					(thickness 0.15)
				)
				(justify left bottom)
				(hide yes)
			)
		)
		(property "Datasheet" "https://product.tdk.com/en/search/capacitor/ceramic/mlcc/info?part_no=C1005X6S1A105K050BC"
			(at 127 96.52 0)
			(effects
				(font
					(size 1.27 1.27)
					(thickness 0.15)
				)
				(justify left bottom)
				(hide yes)
			)
		)
		(property "Description" ""
			(at 111.76 116.84 0)
			(effects
				(font
					(size 1.27 1.27)
				)
			)
		)
		(property "Manufacturer" "TDK"
			(at 132.08 96.52 0)
			(effects
				(font
					(size 1.27 1.27)
					(thickness 0.15)
				)
				(justify left bottom)
				(hide yes)
			)
		)
		(property "MPN" "C1005X6S1A105K050BC"
			(at 129.54 96.52 0)
			(effects
				(font
					(size 1.27 1.27)
					(thickness 0.15)
				)
				(justify left bottom)
				(hide yes)
			)
		)
		(property "Val" "1u"
			(at 113.665 115.57 90)
			(effects
				(font
					(size 1.27 1.27)
					(thickness 0.15)
				)
				(justify right)
			)
		)
		(property "License" "Apache-2.0"
			(at 134.62 96.52 0)
			(effects
				(font
					(size 1.27 1.27)
					(thickness 0.15)
				)
				(justify left bottom)
				(hide yes)
			)
		)
		(property "Author" "Antmicro"
			(at 137.16 96.52 0)
			(effects
				(font
					(size 1.27 1.27)
					(thickness 0.15)
				)
				(justify left bottom)
				(hide yes)
			)
		)
		(property "Voltage" ""
			(at 139.7 96.52 0)
			(effects
				(font
					(size 1.27 1.27)
				)
				(justify left bottom)
				(hide yes)
			)
		)
		(property "Dielectric" ""
			(at 142.24 96.52 0)
			(effects
				(font
					(size 1.27 1.27)
				)
				(justify left bottom)
				(hide yes)
			)
		)
		(pin "1"
		)
		(pin "2"
		)
		(instances
			(project "k410t-devboard"
				(path ""
					(reference "C215")
					(unit 1)
				)
			)
		)
	)
	(symbol
		(lib_id "antmicropower:GND")
		(at 115.57 220.98 0)
		(unit 1)
		(exclude_from_sim no)
		(in_bom yes)
		(on_board yes)
		(dnp no)
		(property "Reference" "#PWR0158"
			(at 115.57 227.33 0)
			(effects
				(font
					(size 1.27 1.27)
				)
				(hide yes)
			)
		)
		(property "Value" "GND"
			(at 115.57 224.79 0)
			(effects
				(font
					(size 1.27 1.27)
				)
			)
		)
		(property "Footprint" ""
			(at 124.46 228.6 0)
			(effects
				(font
					(size 1.27 1.27)
					(thickness 0.15)
				)
				(justify left bottom)
				(hide yes)
			)
		)
		(property "Datasheet" ""
			(at 124.46 233.68 0)
			(effects
				(font
					(size 1.27 1.27)
					(thickness 0.15)
				)
				(justify left bottom)
				(hide yes)
			)
		)
		(property "Description" ""
			(at 115.57 220.98 0)
			(effects
				(font
					(size 1.27 1.27)
				)
			)
		)
		(property "Author" "Antmicro"
			(at 124.46 228.6 0)
			(effects
				(font
					(size 1.27 1.27)
					(thickness 0.15)
				)
				(justify left bottom)
				(hide yes)
			)
		)
		(property "License" "Apache-2.0"
			(at 124.46 231.14 0)
			(effects
				(font
					(size 1.27 1.27)
					(thickness 0.15)
				)
				(justify left bottom)
				(hide yes)
			)
		)
		(pin "1"
		)
		(instances
			(project "k410t-devboard"
				(path ""
					(reference "#PWR0158")
					(unit 1)
				)
			)
		)
	)
	(symbol
		(lib_id "antmicroResistors0402:R_100R_0402")
		(at 356.87 33.02 180)
		(unit 1)
		(exclude_from_sim no)
		(in_bom yes)
		(on_board yes)
		(dnp no)
		(property "Reference" "R142"
			(at 359.41 31.75 0)
			(effects
				(font
					(size 1.27 1.27)
				)
			)
		)
		(property "Value" "R_100R_0402"
			(at 336.55 20.32 0)
			(effects
				(font
					(size 1.27 1.27)
					(thickness 0.15)
				)
				(justify left bottom)
				(hide yes)
			)
		)
		(property "Footprint" "antmicro-footprints:R_0402_1005Metric"
			(at 336.55 17.78 0)
			(effects
				(font
					(size 1.27 1.27)
					(thickness 0.15)
				)
				(justify left bottom)
				(hide yes)
			)
		)
		(property "Datasheet" "https://www.bourns.com/docs/product-datasheets/cr.pdf"
			(at 336.55 15.24 0)
			(effects
				(font
					(size 1.27 1.27)
					(thickness 0.15)
				)
				(justify left bottom)
				(hide yes)
			)
		)
		(property "Description" ""
			(at 356.87 33.02 0)
			(effects
				(font
					(size 1.27 1.27)
				)
			)
		)
		(property "Manufacturer" "Bourns"
			(at 336.55 10.16 0)
			(effects
				(font
					(size 1.27 1.27)
					(thickness 0.15)
				)
				(justify left bottom)
				(hide yes)
			)
		)
		(property "MPN" "CR0402-FX-1000GLF"
			(at 336.55 12.7 0)
			(effects
				(font
					(size 1.27 1.27)
					(thickness 0.15)
				)
				(justify left bottom)
				(hide yes)
			)
		)
		(property "Val" "100R"
			(at 349.25 31.75 0)
			(effects
				(font
					(size 1.27 1.27)
					(thickness 0.15)
				)
			)
		)
		(property "License" "Apache-2.0"
			(at 336.55 7.62 0)
			(effects
				(font
					(size 1.27 1.27)
					(thickness 0.15)
				)
				(justify left bottom)
				(hide yes)
			)
		)
		(property "Author" "Antmicro"
			(at 336.55 5.08 0)
			(effects
				(font
					(size 1.27 1.27)
					(thickness 0.15)
				)
				(justify left bottom)
				(hide yes)
			)
		)
		(property "Tolerance" "1%"
			(at 336.55 22.86 0)
			(effects
				(font
					(size 1.27 1.27)
				)
				(justify left bottom)
				(hide yes)
			)
		)
		(pin "1"
		)
		(pin "2"
		)
		(instances
			(project "k410t-devboard"
				(path ""
					(reference "R142")
					(unit 1)
				)
			)
		)
	)
	(symbol
		(lib_id "antmicroResistors0402:R_100R_0402")
		(at 356.87 43.18 180)
		(unit 1)
		(exclude_from_sim no)
		(in_bom yes)
		(on_board yes)
		(dnp no)
		(property "Reference" "R145"
			(at 359.41 41.91 0)
			(effects
				(font
					(size 1.27 1.27)
				)
			)
		)
		(property "Value" "R_100R_0402"
			(at 336.55 30.48 0)
			(effects
				(font
					(size 1.27 1.27)
					(thickness 0.15)
				)
				(justify left bottom)
				(hide yes)
			)
		)
		(property "Footprint" "antmicro-footprints:R_0402_1005Metric"
			(at 336.55 27.94 0)
			(effects
				(font
					(size 1.27 1.27)
					(thickness 0.15)
				)
				(justify left bottom)
				(hide yes)
			)
		)
		(property "Datasheet" "https://www.bourns.com/docs/product-datasheets/cr.pdf"
			(at 336.55 25.4 0)
			(effects
				(font
					(size 1.27 1.27)
					(thickness 0.15)
				)
				(justify left bottom)
				(hide yes)
			)
		)
		(property "Description" ""
			(at 356.87 43.18 0)
			(effects
				(font
					(size 1.27 1.27)
				)
			)
		)
		(property "Manufacturer" "Bourns"
			(at 336.55 20.32 0)
			(effects
				(font
					(size 1.27 1.27)
					(thickness 0.15)
				)
				(justify left bottom)
				(hide yes)
			)
		)
		(property "MPN" "CR0402-FX-1000GLF"
			(at 336.55 22.86 0)
			(effects
				(font
					(size 1.27 1.27)
					(thickness 0.15)
				)
				(justify left bottom)
				(hide yes)
			)
		)
		(property "Val" "100R"
			(at 349.25 41.91 0)
			(effects
				(font
					(size 1.27 1.27)
					(thickness 0.15)
				)
			)
		)
		(property "License" "Apache-2.0"
			(at 336.55 17.78 0)
			(effects
				(font
					(size 1.27 1.27)
					(thickness 0.15)
				)
				(justify left bottom)
				(hide yes)
			)
		)
		(property "Author" "Antmicro"
			(at 336.55 15.24 0)
			(effects
				(font
					(size 1.27 1.27)
					(thickness 0.15)
				)
				(justify left bottom)
				(hide yes)
			)
		)
		(property "Tolerance" "1%"
			(at 336.55 33.02 0)
			(effects
				(font
					(size 1.27 1.27)
				)
				(justify left bottom)
				(hide yes)
			)
		)
		(pin "1"
		)
		(pin "2"
		)
		(instances
			(project "k410t-devboard"
				(path ""
					(reference "R145")
					(unit 1)
				)
			)
		)
	)
	(symbol
		(lib_id "antmicropower:GND")
		(at 302.26 99.695 0)
		(unit 1)
		(exclude_from_sim no)
		(in_bom yes)
		(on_board yes)
		(dnp no)
		(property "Reference" "#PWR0801"
			(at 302.26 106.045 0)
			(effects
				(font
					(size 1.27 1.27)
				)
				(hide yes)
			)
		)
		(property "Value" "GND"
			(at 302.26 103.505 0)
			(effects
				(font
					(size 1.27 1.27)
				)
			)
		)
		(property "Footprint" ""
			(at 311.15 107.315 0)
			(effects
				(font
					(size 1.27 1.27)
					(thickness 0.15)
				)
				(justify left bottom)
				(hide yes)
			)
		)
		(property "Datasheet" ""
			(at 311.15 112.395 0)
			(effects
				(font
					(size 1.27 1.27)
					(thickness 0.15)
				)
				(justify left bottom)
				(hide yes)
			)
		)
		(property "Description" ""
			(at 302.26 99.695 0)
			(effects
				(font
					(size 1.27 1.27)
				)
			)
		)
		(property "Author" "Antmicro"
			(at 311.15 107.315 0)
			(effects
				(font
					(size 1.27 1.27)
					(thickness 0.15)
				)
				(justify left bottom)
				(hide yes)
			)
		)
		(property "License" "Apache-2.0"
			(at 311.15 109.855 0)
			(effects
				(font
					(size 1.27 1.27)
					(thickness 0.15)
				)
				(justify left bottom)
				(hide yes)
			)
		)
		(pin "1"
		)
		(instances
			(project "k410t-devboard"
				(path ""
					(reference "#PWR0801")
					(unit 1)
				)
			)
		)
	)
	(symbol
		(lib_id "antmicroResistors0402:R_10k_0402")
		(at 354.33 102.87 270)
		(unit 1)
		(exclude_from_sim no)
		(in_bom yes)
		(on_board yes)
		(dnp no)
		(fields_autoplaced yes)
		(property "Reference" "R149"
			(at 356.235 104.1399 90)
			(effects
				(font
					(size 1.27 1.27)
				)
				(justify left)
			)
		)
		(property "Value" "R_10k_0402"
			(at 341.63 123.19 0)
			(effects
				(font
					(size 1.27 1.27)
					(thickness 0.15)
				)
				(justify left bottom)
				(hide yes)
			)
		)
		(property "Footprint" "antmicro-footprints:R_0402_1005Metric"
			(at 339.09 123.19 0)
			(effects
				(font
					(size 1.27 1.27)
					(thickness 0.15)
				)
				(justify left bottom)
				(hide yes)
			)
		)
		(property "Datasheet" "https://www.bourns.com/docs/product-datasheets/cr.pdf"
			(at 336.55 123.19 0)
			(effects
				(font
					(size 1.27 1.27)
					(thickness 0.15)
				)
				(justify left bottom)
				(hide yes)
			)
		)
		(property "Description" ""
			(at 354.33 102.87 0)
			(effects
				(font
					(size 1.27 1.27)
				)
			)
		)
		(property "Manufacturer" "Bourns"
			(at 331.47 123.19 0)
			(effects
				(font
					(size 1.27 1.27)
					(thickness 0.15)
				)
				(justify left bottom)
				(hide yes)
			)
		)
		(property "MPN" "CR0402-FX-1002GLF"
			(at 334.01 123.19 0)
			(effects
				(font
					(size 1.27 1.27)
					(thickness 0.15)
				)
				(justify left bottom)
				(hide yes)
			)
		)
		(property "Val" "10k"
			(at 356.235 106.6799 90)
			(effects
				(font
					(size 1.27 1.27)
					(thickness 0.15)
				)
				(justify left)
			)
		)
		(property "License" "Apache-2.0"
			(at 328.93 123.19 0)
			(effects
				(font
					(size 1.27 1.27)
					(thickness 0.15)
				)
				(justify left bottom)
				(hide yes)
			)
		)
		(property "Author" "Antmicro"
			(at 326.39 123.19 0)
			(effects
				(font
					(size 1.27 1.27)
					(thickness 0.15)
				)
				(justify left bottom)
				(hide yes)
			)
		)
		(property "Tolerance" "1%"
			(at 344.17 123.19 0)
			(effects
				(font
					(size 1.27 1.27)
				)
				(justify left bottom)
				(hide yes)
			)
		)
		(pin "1"
		)
		(pin "2"
		)
		(instances
			(project "k410t-devboard"
				(path ""
					(reference "R149")
					(unit 1)
				)
			)
		)
	)
	(symbol
		(lib_id "antmicroResistors0402:R_100R_0402")
		(at 279.4 45.72 180)
		(unit 1)
		(exclude_from_sim no)
		(in_bom yes)
		(on_board yes)
		(dnp no)
		(property "Reference" "R138"
			(at 281.94 44.45 0)
			(effects
				(font
					(size 1.27 1.27)
				)
			)
		)
		(property "Value" "R_100R_0402"
			(at 259.08 33.02 0)
			(effects
				(font
					(size 1.27 1.27)
					(thickness 0.15)
				)
				(justify left bottom)
				(hide yes)
			)
		)
		(property "Footprint" "antmicro-footprints:R_0402_1005Metric"
			(at 259.08 30.48 0)
			(effects
				(font
					(size 1.27 1.27)
					(thickness 0.15)
				)
				(justify left bottom)
				(hide yes)
			)
		)
		(property "Datasheet" "https://www.bourns.com/docs/product-datasheets/cr.pdf"
			(at 259.08 27.94 0)
			(effects
				(font
					(size 1.27 1.27)
					(thickness 0.15)
				)
				(justify left bottom)
				(hide yes)
			)
		)
		(property "Description" ""
			(at 279.4 45.72 0)
			(effects
				(font
					(size 1.27 1.27)
				)
			)
		)
		(property "Manufacturer" "Bourns"
			(at 259.08 22.86 0)
			(effects
				(font
					(size 1.27 1.27)
					(thickness 0.15)
				)
				(justify left bottom)
				(hide yes)
			)
		)
		(property "MPN" "CR0402-FX-1000GLF"
			(at 259.08 25.4 0)
			(effects
				(font
					(size 1.27 1.27)
					(thickness 0.15)
				)
				(justify left bottom)
				(hide yes)
			)
		)
		(property "Val" "100R"
			(at 271.78 44.45 0)
			(effects
				(font
					(size 1.27 1.27)
					(thickness 0.15)
				)
			)
		)
		(property "License" "Apache-2.0"
			(at 259.08 20.32 0)
			(effects
				(font
					(size 1.27 1.27)
					(thickness 0.15)
				)
				(justify left bottom)
				(hide yes)
			)
		)
		(property "Author" "Antmicro"
			(at 259.08 17.78 0)
			(effects
				(font
					(size 1.27 1.27)
					(thickness 0.15)
				)
				(justify left bottom)
				(hide yes)
			)
		)
		(property "Tolerance" "1%"
			(at 259.08 35.56 0)
			(effects
				(font
					(size 1.27 1.27)
				)
				(justify left bottom)
				(hide yes)
			)
		)
		(pin "1"
		)
		(pin "2"
		)
		(instances
			(project "k410t-devboard"
				(path ""
					(reference "R138")
					(unit 1)
				)
			)
		)
	)
	(symbol
		(lib_id "antmicropower:GND")
		(at 120.65 100.33 0)
		(mirror y)
		(unit 1)
		(exclude_from_sim no)
		(in_bom yes)
		(on_board yes)
		(dnp no)
		(property "Reference" "#PWR0161"
			(at 120.65 106.68 0)
			(effects
				(font
					(size 1.27 1.27)
				)
				(hide yes)
			)
		)
		(property "Value" "GND"
			(at 120.65 104.14 0)
			(effects
				(font
					(size 1.27 1.27)
				)
			)
		)
		(property "Footprint" ""
			(at 111.76 107.95 0)
			(effects
				(font
					(size 1.27 1.27)
					(thickness 0.15)
				)
				(justify left bottom)
				(hide yes)
			)
		)
		(property "Datasheet" ""
			(at 111.76 113.03 0)
			(effects
				(font
					(size 1.27 1.27)
					(thickness 0.15)
				)
				(justify left bottom)
				(hide yes)
			)
		)
		(property "Description" ""
			(at 120.65 100.33 0)
			(effects
				(font
					(size 1.27 1.27)
				)
			)
		)
		(property "Author" "Antmicro"
			(at 111.76 107.95 0)
			(effects
				(font
					(size 1.27 1.27)
					(thickness 0.15)
				)
				(justify left bottom)
				(hide yes)
			)
		)
		(property "License" "Apache-2.0"
			(at 111.76 110.49 0)
			(effects
				(font
					(size 1.27 1.27)
					(thickness 0.15)
				)
				(justify left bottom)
				(hide yes)
			)
		)
		(pin "1"
		)
		(instances
			(project "k410t-devboard"
				(path ""
					(reference "#PWR0161")
					(unit 1)
				)
			)
		)
	)
	(symbol
		(lib_id "antmicropower:GND")
		(at 104.14 156.21 0)
		(unit 1)
		(exclude_from_sim no)
		(in_bom yes)
		(on_board yes)
		(dnp no)
		(property "Reference" "#PWR0141"
			(at 104.14 162.56 0)
			(effects
				(font
					(size 1.27 1.27)
				)
				(hide yes)
			)
		)
		(property "Value" "GND"
			(at 104.14 160.02 0)
			(effects
				(font
					(size 1.27 1.27)
				)
			)
		)
		(property "Footprint" ""
			(at 113.03 163.83 0)
			(effects
				(font
					(size 1.27 1.27)
					(thickness 0.15)
				)
				(justify left bottom)
				(hide yes)
			)
		)
		(property "Datasheet" ""
			(at 113.03 168.91 0)
			(effects
				(font
					(size 1.27 1.27)
					(thickness 0.15)
				)
				(justify left bottom)
				(hide yes)
			)
		)
		(property "Description" ""
			(at 104.14 156.21 0)
			(effects
				(font
					(size 1.27 1.27)
				)
			)
		)
		(property "Author" "Antmicro"
			(at 113.03 163.83 0)
			(effects
				(font
					(size 1.27 1.27)
					(thickness 0.15)
				)
				(justify left bottom)
				(hide yes)
			)
		)
		(property "License" "Apache-2.0"
			(at 113.03 166.37 0)
			(effects
				(font
					(size 1.27 1.27)
					(thickness 0.15)
				)
				(justify left bottom)
				(hide yes)
			)
		)
		(pin "1"
		)
		(instances
			(project "k410t-devboard"
				(path ""
					(reference "#PWR0141")
					(unit 1)
				)
			)
		)
	)
	(symbol
		(lib_id "antmicropower:GND")
		(at 308.61 241.3 0)
		(mirror y)
		(unit 1)
		(exclude_from_sim no)
		(in_bom yes)
		(on_board yes)
		(dnp no)
		(property "Reference" "#PWR0189"
			(at 308.61 247.65 0)
			(effects
				(font
					(size 1.27 1.27)
				)
				(hide yes)
			)
		)
		(property "Value" "GND"
			(at 308.61 245.11 0)
			(effects
				(font
					(size 1.27 1.27)
				)
			)
		)
		(property "Footprint" ""
			(at 299.72 248.92 0)
			(effects
				(font
					(size 1.27 1.27)
					(thickness 0.15)
				)
				(justify left bottom)
				(hide yes)
			)
		)
		(property "Datasheet" ""
			(at 299.72 254 0)
			(effects
				(font
					(size 1.27 1.27)
					(thickness 0.15)
				)
				(justify left bottom)
				(hide yes)
			)
		)
		(property "Description" ""
			(at 308.61 241.3 0)
			(effects
				(font
					(size 1.27 1.27)
				)
			)
		)
		(property "Author" "Antmicro"
			(at 299.72 248.92 0)
			(effects
				(font
					(size 1.27 1.27)
					(thickness 0.15)
				)
				(justify left bottom)
				(hide yes)
			)
		)
		(property "License" "Apache-2.0"
			(at 299.72 251.46 0)
			(effects
				(font
					(size 1.27 1.27)
					(thickness 0.15)
				)
				(justify left bottom)
				(hide yes)
			)
		)
		(pin "1"
		)
		(instances
			(project "k410t-devboard"
				(path ""
					(reference "#PWR0189")
					(unit 1)
				)
			)
		)
	)
	(symbol
		(lib_id "antmicroResistors0402:R_100k_0402")
		(at 107.95 163.83 0)
		(unit 1)
		(exclude_from_sim no)
		(in_bom yes)
		(on_board yes)
		(dnp no)
		(property "Reference" "R353"
			(at 110.49 158.75 0)
			(effects
				(font
					(size 1.27 1.27)
				)
			)
		)
		(property "Value" "R_100k_0402"
			(at 128.27 176.53 0)
			(effects
				(font
					(size 1.27 1.27)
					(thickness 0.15)
				)
				(justify left bottom)
				(hide yes)
			)
		)
		(property "Footprint" "antmicro-footprints:R_0402_1005Metric"
			(at 128.27 179.07 0)
			(effects
				(font
					(size 1.27 1.27)
					(thickness 0.15)
				)
				(justify left bottom)
				(hide yes)
			)
		)
		(property "Datasheet" "https://www.bourns.com/docs/product-datasheets/cr.pdf"
			(at 128.27 181.61 0)
			(effects
				(font
					(size 1.27 1.27)
					(thickness 0.15)
				)
				(justify left bottom)
				(hide yes)
			)
		)
		(property "Description" ""
			(at 107.95 163.83 0)
			(effects
				(font
					(size 1.27 1.27)
				)
			)
		)
		(property "Manufacturer" "Bourns"
			(at 128.27 186.69 0)
			(effects
				(font
					(size 1.27 1.27)
					(thickness 0.15)
				)
				(justify left bottom)
				(hide yes)
			)
		)
		(property "MPN" "CR0402-FX-1003GLF"
			(at 128.27 184.15 0)
			(effects
				(font
					(size 1.27 1.27)
					(thickness 0.15)
				)
				(justify left bottom)
				(hide yes)
			)
		)
		(property "Val" "100k"
			(at 110.49 161.29 0)
			(effects
				(font
					(size 1.27 1.27)
					(thickness 0.15)
				)
			)
		)
		(property "License" "Apache-2.0"
			(at 128.27 189.23 0)
			(effects
				(font
					(size 1.27 1.27)
					(thickness 0.15)
				)
				(justify left bottom)
				(hide yes)
			)
		)
		(property "Author" "Antmicro"
			(at 128.27 191.77 0)
			(effects
				(font
					(size 1.27 1.27)
					(thickness 0.15)
				)
				(justify left bottom)
				(hide yes)
			)
		)
		(property "Tolerance" "1%"
			(at 128.27 173.99 0)
			(effects
				(font
					(size 1.27 1.27)
				)
				(justify left bottom)
				(hide yes)
			)
		)
		(pin "1"
		)
		(pin "2"
		)
		(instances
			(project "k410t-devboard"
				(path ""
					(reference "R353")
					(unit 1)
				)
			)
		)
	)
	(symbol
		(lib_id "antmicroResistors0402:R_100k_0402")
		(at 107.95 182.88 0)
		(unit 1)
		(exclude_from_sim no)
		(in_bom yes)
		(on_board yes)
		(dnp no)
		(property "Reference" "R354"
			(at 110.49 177.8 0)
			(effects
				(font
					(size 1.27 1.27)
				)
			)
		)
		(property "Value" "R_100k_0402"
			(at 128.27 195.58 0)
			(effects
				(font
					(size 1.27 1.27)
					(thickness 0.15)
				)
				(justify left bottom)
				(hide yes)
			)
		)
		(property "Footprint" "antmicro-footprints:R_0402_1005Metric"
			(at 128.27 198.12 0)
			(effects
				(font
					(size 1.27 1.27)
					(thickness 0.15)
				)
				(justify left bottom)
				(hide yes)
			)
		)
		(property "Datasheet" "https://www.bourns.com/docs/product-datasheets/cr.pdf"
			(at 128.27 200.66 0)
			(effects
				(font
					(size 1.27 1.27)
					(thickness 0.15)
				)
				(justify left bottom)
				(hide yes)
			)
		)
		(property "Description" ""
			(at 107.95 182.88 0)
			(effects
				(font
					(size 1.27 1.27)
				)
			)
		)
		(property "Manufacturer" "Bourns"
			(at 128.27 205.74 0)
			(effects
				(font
					(size 1.27 1.27)
					(thickness 0.15)
				)
				(justify left bottom)
				(hide yes)
			)
		)
		(property "MPN" "CR0402-FX-1003GLF"
			(at 128.27 203.2 0)
			(effects
				(font
					(size 1.27 1.27)
					(thickness 0.15)
				)
				(justify left bottom)
				(hide yes)
			)
		)
		(property "Val" "100k"
			(at 110.49 180.34 0)
			(effects
				(font
					(size 1.27 1.27)
					(thickness 0.15)
				)
			)
		)
		(property "License" "Apache-2.0"
			(at 128.27 208.28 0)
			(effects
				(font
					(size 1.27 1.27)
					(thickness 0.15)
				)
				(justify left bottom)
				(hide yes)
			)
		)
		(property "Author" "Antmicro"
			(at 128.27 210.82 0)
			(effects
				(font
					(size 1.27 1.27)
					(thickness 0.15)
				)
				(justify left bottom)
				(hide yes)
			)
		)
		(property "Tolerance" "1%"
			(at 128.27 193.04 0)
			(effects
				(font
					(size 1.27 1.27)
				)
				(justify left bottom)
				(hide yes)
			)
		)
		(pin "1"
		)
		(pin "2"
		)
		(instances
			(project "k410t-devboard"
				(path ""
					(reference "R354")
					(unit 1)
				)
			)
		)
	)
	(symbol
		(lib_id "antmicropower:+1V8")
		(at 223.52 255.27 0)
		(unit 1)
		(exclude_from_sim no)
		(in_bom yes)
		(on_board yes)
		(dnp no)
		(property "Reference" "#PWR0163"
			(at 223.52 259.08 0)
			(effects
				(font
					(size 1.27 1.27)
				)
				(hide yes)
			)
		)
		(property "Value" "+1V8"
			(at 223.52 251.714 0)
			(effects
				(font
					(size 1.27 1.27)
				)
			)
		)
		(property "Footprint" ""
			(at 238.76 262.89 0)
			(effects
				(font
					(size 1.27 1.27)
					(thickness 0.15)
				)
				(justify left bottom)
				(hide yes)
			)
		)
		(property "Datasheet" ""
			(at 238.76 265.43 0)
			(effects
				(font
					(size 1.27 1.27)
					(thickness 0.15)
				)
				(justify left bottom)
				(hide yes)
			)
		)
		(property "Description" ""
			(at 223.52 255.27 0)
			(effects
				(font
					(size 1.27 1.27)
				)
			)
		)
		(property "Author" "Antmicro"
			(at 238.76 262.89 0)
			(effects
				(font
					(size 1.27 1.27)
					(thickness 0.15)
				)
				(justify left bottom)
				(hide yes)
			)
		)
		(property "License" "Apache-2.0"
			(at 238.76 265.43 0)
			(effects
				(font
					(size 1.27 1.27)
					(thickness 0.15)
				)
				(justify left bottom)
				(hide yes)
			)
		)
		(pin "1"
		)
		(instances
			(project "k410t-devboard"
				(path ""
					(reference "#PWR0163")
					(unit 1)
				)
			)
		)
	)
	(symbol
		(lib_id "antmicroResistors0402:R_1k_0402")
		(at 72.39 250.19 90)
		(unit 1)
		(exclude_from_sim no)
		(in_bom yes)
		(on_board yes)
		(dnp no)
		(fields_autoplaced yes)
		(property "Reference" "R111"
			(at 69.85 246.3799 90)
			(effects
				(font
					(size 1.27 1.27)
				)
				(justify left)
			)
		)
		(property "Value" "R_1k_0402"
			(at 85.09 229.87 0)
			(effects
				(font
					(size 1.27 1.27)
					(thickness 0.15)
				)
				(justify left bottom)
				(hide yes)
			)
		)
		(property "Footprint" "antmicro-footprints:R_0402_1005Metric"
			(at 87.63 229.87 0)
			(effects
				(font
					(size 1.27 1.27)
					(thickness 0.15)
				)
				(justify left bottom)
				(hide yes)
			)
		)
		(property "Datasheet" "https://www.bourns.com/docs/product-datasheets/cr.pdf"
			(at 90.17 229.87 0)
			(effects
				(font
					(size 1.27 1.27)
					(thickness 0.15)
				)
				(justify left bottom)
				(hide yes)
			)
		)
		(property "Description" ""
			(at 72.39 250.19 0)
			(effects
				(font
					(size 1.27 1.27)
				)
			)
		)
		(property "Manufacturer" "Bourns"
			(at 95.25 229.87 0)
			(effects
				(font
					(size 1.27 1.27)
					(thickness 0.15)
				)
				(justify left bottom)
				(hide yes)
			)
		)
		(property "MPN" "CR0402-FX-1001GLF"
			(at 92.71 229.87 0)
			(effects
				(font
					(size 1.27 1.27)
					(thickness 0.15)
				)
				(justify left bottom)
				(hide yes)
			)
		)
		(property "Val" "1k"
			(at 69.85 248.9199 90)
			(effects
				(font
					(size 1.27 1.27)
					(thickness 0.15)
				)
				(justify left)
			)
		)
		(property "License" "Apache-2.0"
			(at 97.79 229.87 0)
			(effects
				(font
					(size 1.27 1.27)
					(thickness 0.15)
				)
				(justify left bottom)
				(hide yes)
			)
		)
		(property "Author" "Antmicro"
			(at 100.33 229.87 0)
			(effects
				(font
					(size 1.27 1.27)
					(thickness 0.15)
				)
				(justify left bottom)
				(hide yes)
			)
		)
		(property "Tolerance" "1%"
			(at 82.55 229.87 0)
			(effects
				(font
					(size 1.27 1.27)
				)
				(justify left bottom)
				(hide yes)
			)
		)
		(pin "1"
		)
		(pin "2"
		)
		(instances
			(project "k410t-devboard"
				(path ""
					(reference "R111")
					(unit 1)
				)
			)
		)
	)
	(symbol
		(lib_id "antmicropower:GND")
		(at 186.69 194.31 0)
		(unit 1)
		(exclude_from_sim no)
		(in_bom yes)
		(on_board yes)
		(dnp no)
		(property "Reference" "#PWR0172"
			(at 186.69 200.66 0)
			(effects
				(font
					(size 1.27 1.27)
				)
				(hide yes)
			)
		)
		(property "Value" "GND"
			(at 186.69 198.12 0)
			(effects
				(font
					(size 1.27 1.27)
				)
			)
		)
		(property "Footprint" ""
			(at 195.58 201.93 0)
			(effects
				(font
					(size 1.27 1.27)
					(thickness 0.15)
				)
				(justify left bottom)
				(hide yes)
			)
		)
		(property "Datasheet" ""
			(at 195.58 207.01 0)
			(effects
				(font
					(size 1.27 1.27)
					(thickness 0.15)
				)
				(justify left bottom)
				(hide yes)
			)
		)
		(property "Description" ""
			(at 186.69 194.31 0)
			(effects
				(font
					(size 1.27 1.27)
				)
			)
		)
		(property "Author" "Antmicro"
			(at 195.58 201.93 0)
			(effects
				(font
					(size 1.27 1.27)
					(thickness 0.15)
				)
				(justify left bottom)
				(hide yes)
			)
		)
		(property "License" "Apache-2.0"
			(at 195.58 204.47 0)
			(effects
				(font
					(size 1.27 1.27)
					(thickness 0.15)
				)
				(justify left bottom)
				(hide yes)
			)
		)
		(pin "1"
		)
		(instances
			(project "k410t-devboard"
				(path ""
					(reference "#PWR0172")
					(unit 1)
				)
			)
		)
	)
	(symbol
		(lib_id "antmicroResistors0402:R_1k_0402")
		(at 137.16 193.04 0)
		(unit 1)
		(exclude_from_sim no)
		(in_bom yes)
		(on_board yes)
		(dnp no)
		(property "Reference" "R130"
			(at 139.7 187.96 0)
			(effects
				(font
					(size 1.27 1.27)
				)
			)
		)
		(property "Value" "R_1k_0402"
			(at 157.48 205.74 0)
			(effects
				(font
					(size 1.27 1.27)
					(thickness 0.15)
				)
				(justify left bottom)
				(hide yes)
			)
		)
		(property "Footprint" "antmicro-footprints:R_0402_1005Metric"
			(at 157.48 208.28 0)
			(effects
				(font
					(size 1.27 1.27)
					(thickness 0.15)
				)
				(justify left bottom)
				(hide yes)
			)
		)
		(property "Datasheet" "https://www.bourns.com/docs/product-datasheets/cr.pdf"
			(at 157.48 210.82 0)
			(effects
				(font
					(size 1.27 1.27)
					(thickness 0.15)
				)
				(justify left bottom)
				(hide yes)
			)
		)
		(property "Description" ""
			(at 137.16 193.04 0)
			(effects
				(font
					(size 1.27 1.27)
				)
			)
		)
		(property "Manufacturer" "Bourns"
			(at 157.48 215.9 0)
			(effects
				(font
					(size 1.27 1.27)
					(thickness 0.15)
				)
				(justify left bottom)
				(hide yes)
			)
		)
		(property "MPN" "CR0402-FX-1001GLF"
			(at 157.48 213.36 0)
			(effects
				(font
					(size 1.27 1.27)
					(thickness 0.15)
				)
				(justify left bottom)
				(hide yes)
			)
		)
		(property "Val" "1k"
			(at 139.7 190.5 0)
			(effects
				(font
					(size 1.27 1.27)
					(thickness 0.15)
				)
			)
		)
		(property "License" "Apache-2.0"
			(at 157.48 218.44 0)
			(effects
				(font
					(size 1.27 1.27)
					(thickness 0.15)
				)
				(justify left bottom)
				(hide yes)
			)
		)
		(property "Author" "Antmicro"
			(at 157.48 220.98 0)
			(effects
				(font
					(size 1.27 1.27)
					(thickness 0.15)
				)
				(justify left bottom)
				(hide yes)
			)
		)
		(property "Tolerance" "1%"
			(at 157.48 203.2 0)
			(effects
				(font
					(size 1.27 1.27)
				)
				(justify left bottom)
				(hide yes)
			)
		)
		(pin "1"
		)
		(pin "2"
		)
		(instances
			(project "k410t-devboard"
				(path ""
					(reference "R130")
					(unit 1)
				)
			)
		)
	)
	(symbol
		(lib_id "antmicroLEDIndicationDiscrete:LED_R_0603_KP-1608EC")
		(at 158.75 193.04 0)
		(mirror y)
		(unit 1)
		(exclude_from_sim no)
		(in_bom yes)
		(on_board yes)
		(dnp no)
		(property "Reference" "D24"
			(at 154.94 185.42 0)
			(effects
				(font
					(size 1.27 1.27)
				)
			)
		)
		(property "Value" "LED_R_0603_KP-1608EC"
			(at 154.94 196.215 0)
			(effects
				(font
					(size 1.27 1.27)
					(thickness 0.15)
				)
				(hide yes)
			)
		)
		(property "Footprint" "antmicro-footprints:LED_0603_1608Metric_R"
			(at 135.89 203.2 0)
			(effects
				(font
					(size 1.27 1.27)
					(thickness 0.15)
				)
				(justify left bottom)
				(hide yes)
			)
		)
		(property "Datasheet" "http://www.kingbright.com/attachments/file/psearch/000/00/20131112/KP-1608EC(Ver.14A).pdf"
			(at 135.89 205.74 0)
			(effects
				(font
					(size 1.27 1.27)
					(thickness 0.15)
				)
				(justify left bottom)
				(hide yes)
			)
		)
		(property "Description" ""
			(at 158.75 193.04 0)
			(effects
				(font
					(size 1.27 1.27)
				)
			)
		)
		(property "MPN" "KP-1608EC"
			(at 135.89 208.28 0)
			(effects
				(font
					(size 1.27 1.27)
					(thickness 0.15)
				)
				(justify left bottom)
				(hide yes)
			)
		)
		(property "Manufacturer" "Kingbright"
			(at 135.89 210.82 0)
			(effects
				(font
					(size 1.27 1.27)
					(thickness 0.15)
				)
				(justify left bottom)
				(hide yes)
			)
		)
		(property "Author" "Antmicro"
			(at 135.89 213.36 0)
			(effects
				(font
					(size 1.27 1.27)
					(thickness 0.15)
				)
				(justify left bottom)
				(hide yes)
			)
		)
		(property "License" "Apache-2.0"
			(at 135.89 215.9 0)
			(effects
				(font
					(size 1.27 1.27)
					(thickness 0.15)
				)
				(justify left bottom)
				(hide yes)
			)
		)
		(property "Color" "Red"
			(at 154.94 187.96 0)
			(effects
				(font
					(size 1.27 1.27)
				)
			)
		)
		(property "Public" "False"
			(at 138.43 210.82 0)
			(effects
				(font
					(size 1.27 1.27)
				)
				(justify left bottom)
				(hide yes)
			)
		)
		(pin "1"
		)
		(pin "2"
		)
		(instances
			(project "k410t-devboard"
				(path ""
					(reference "D24")
					(unit 1)
				)
			)
		)
	)
	(symbol
		(lib_id "antmicroResistors0402:R_100R_0402")
		(at 87.63 38.1 180)
		(unit 1)
		(exclude_from_sim no)
		(in_bom yes)
		(on_board yes)
		(dnp no)
		(property "Reference" "R115"
			(at 90.17 36.83 0)
			(effects
				(font
					(size 1.27 1.27)
				)
			)
		)
		(property "Value" "R_100R_0402"
			(at 67.31 25.4 0)
			(effects
				(font
					(size 1.27 1.27)
					(thickness 0.15)
				)
				(justify left bottom)
				(hide yes)
			)
		)
		(property "Footprint" "antmicro-footprints:R_0402_1005Metric"
			(at 67.31 22.86 0)
			(effects
				(font
					(size 1.27 1.27)
					(thickness 0.15)
				)
				(justify left bottom)
				(hide yes)
			)
		)
		(property "Datasheet" "https://www.bourns.com/docs/product-datasheets/cr.pdf"
			(at 67.31 20.32 0)
			(effects
				(font
					(size 1.27 1.27)
					(thickness 0.15)
				)
				(justify left bottom)
				(hide yes)
			)
		)
		(property "Description" ""
			(at 87.63 38.1 0)
			(effects
				(font
					(size 1.27 1.27)
				)
			)
		)
		(property "Manufacturer" "Bourns"
			(at 67.31 15.24 0)
			(effects
				(font
					(size 1.27 1.27)
					(thickness 0.15)
				)
				(justify left bottom)
				(hide yes)
			)
		)
		(property "MPN" "CR0402-FX-1000GLF"
			(at 67.31 17.78 0)
			(effects
				(font
					(size 1.27 1.27)
					(thickness 0.15)
				)
				(justify left bottom)
				(hide yes)
			)
		)
		(property "Val" "100R"
			(at 80.01 36.83 0)
			(effects
				(font
					(size 1.27 1.27)
					(thickness 0.15)
				)
			)
		)
		(property "License" "Apache-2.0"
			(at 67.31 12.7 0)
			(effects
				(font
					(size 1.27 1.27)
					(thickness 0.15)
				)
				(justify left bottom)
				(hide yes)
			)
		)
		(property "Author" "Antmicro"
			(at 67.31 10.16 0)
			(effects
				(font
					(size 1.27 1.27)
					(thickness 0.15)
				)
				(justify left bottom)
				(hide yes)
			)
		)
		(property "Tolerance" "1%"
			(at 67.31 27.94 0)
			(effects
				(font
					(size 1.27 1.27)
				)
				(justify left bottom)
				(hide yes)
			)
		)
		(pin "1"
		)
		(pin "2"
		)
		(instances
			(project "k410t-devboard"
				(path ""
					(reference "R115")
					(unit 1)
				)
			)
		)
	)
	(symbol
		(lib_id "antmicropower:GND")
		(at 115.57 203.2 0)
		(unit 1)
		(exclude_from_sim no)
		(in_bom yes)
		(on_board yes)
		(dnp no)
		(property "Reference" "#PWR0157"
			(at 115.57 209.55 0)
			(effects
				(font
					(size 1.27 1.27)
				)
				(hide yes)
			)
		)
		(property "Value" "GND"
			(at 115.57 207.01 0)
			(effects
				(font
					(size 1.27 1.27)
				)
			)
		)
		(property "Footprint" ""
			(at 124.46 210.82 0)
			(effects
				(font
					(size 1.27 1.27)
					(thickness 0.15)
				)
				(justify left bottom)
				(hide yes)
			)
		)
		(property "Datasheet" ""
			(at 124.46 215.9 0)
			(effects
				(font
					(size 1.27 1.27)
					(thickness 0.15)
				)
				(justify left bottom)
				(hide yes)
			)
		)
		(property "Description" ""
			(at 115.57 203.2 0)
			(effects
				(font
					(size 1.27 1.27)
				)
			)
		)
		(property "Author" "Antmicro"
			(at 124.46 210.82 0)
			(effects
				(font
					(size 1.27 1.27)
					(thickness 0.15)
				)
				(justify left bottom)
				(hide yes)
			)
		)
		(property "License" "Apache-2.0"
			(at 124.46 213.36 0)
			(effects
				(font
					(size 1.27 1.27)
					(thickness 0.15)
				)
				(justify left bottom)
				(hide yes)
			)
		)
		(pin "1"
		)
		(instances
			(project "k410t-devboard"
				(path ""
					(reference "#PWR0157")
					(unit 1)
				)
			)
		)
	)
	(symbol
		(lib_id "antmicroResistors0402:R_100R_0402")
		(at 87.63 92.71 180)
		(unit 1)
		(exclude_from_sim no)
		(in_bom yes)
		(on_board yes)
		(dnp no)
		(property "Reference" "R118"
			(at 90.17 91.44 0)
			(effects
				(font
					(size 1.27 1.27)
				)
			)
		)
		(property "Value" "R_100R_0402"
			(at 67.31 80.01 0)
			(effects
				(font
					(size 1.27 1.27)
					(thickness 0.15)
				)
				(justify left bottom)
				(hide yes)
			)
		)
		(property "Footprint" "antmicro-footprints:R_0402_1005Metric"
			(at 67.31 77.47 0)
			(effects
				(font
					(size 1.27 1.27)
					(thickness 0.15)
				)
				(justify left bottom)
				(hide yes)
			)
		)
		(property "Datasheet" "https://www.bourns.com/docs/product-datasheets/cr.pdf"
			(at 67.31 74.93 0)
			(effects
				(font
					(size 1.27 1.27)
					(thickness 0.15)
				)
				(justify left bottom)
				(hide yes)
			)
		)
		(property "Description" ""
			(at 87.63 92.71 0)
			(effects
				(font
					(size 1.27 1.27)
				)
			)
		)
		(property "Manufacturer" "Bourns"
			(at 67.31 69.85 0)
			(effects
				(font
					(size 1.27 1.27)
					(thickness 0.15)
				)
				(justify left bottom)
				(hide yes)
			)
		)
		(property "MPN" "CR0402-FX-1000GLF"
			(at 67.31 72.39 0)
			(effects
				(font
					(size 1.27 1.27)
					(thickness 0.15)
				)
				(justify left bottom)
				(hide yes)
			)
		)
		(property "Val" "100R"
			(at 80.01 91.44 0)
			(effects
				(font
					(size 1.27 1.27)
					(thickness 0.15)
				)
			)
		)
		(property "License" "Apache-2.0"
			(at 67.31 67.31 0)
			(effects
				(font
					(size 1.27 1.27)
					(thickness 0.15)
				)
				(justify left bottom)
				(hide yes)
			)
		)
		(property "Author" "Antmicro"
			(at 67.31 64.77 0)
			(effects
				(font
					(size 1.27 1.27)
					(thickness 0.15)
				)
				(justify left bottom)
				(hide yes)
			)
		)
		(property "Tolerance" "1%"
			(at 67.31 82.55 0)
			(effects
				(font
					(size 1.27 1.27)
				)
				(justify left bottom)
				(hide yes)
			)
		)
		(pin "1"
		)
		(pin "2"
		)
		(instances
			(project "k410t-devboard"
				(path ""
					(reference "R118")
					(unit 1)
				)
			)
		)
	)
	(symbol
		(lib_id "antmicropower:+3.3V")
		(at 49.53 189.23 0)
		(unit 1)
		(exclude_from_sim no)
		(in_bom yes)
		(on_board yes)
		(dnp no)
		(fields_autoplaced yes)
		(property "Reference" "#PWR0130"
			(at 49.53 193.04 0)
			(effects
				(font
					(size 1.27 1.27)
				)
				(hide yes)
			)
		)
		(property "Value" "+3V3"
			(at 49.53 185.674 0)
			(effects
				(font
					(size 1.27 1.27)
				)
			)
		)
		(property "Footprint" ""
			(at 49.53 189.23 0)
			(effects
				(font
					(size 1.27 1.27)
				)
				(hide yes)
			)
		)
		(property "Datasheet" ""
			(at 49.53 189.23 0)
			(effects
				(font
					(size 1.27 1.27)
				)
				(hide yes)
			)
		)
		(property "Description" ""
			(at 49.53 189.23 0)
			(effects
				(font
					(size 1.27 1.27)
				)
			)
		)
		(pin "1"
		)
		(instances
			(project "k410t-devboard"
				(path ""
					(reference "#PWR0130")
					(unit 1)
				)
			)
		)
	)
	(symbol
		(lib_id "antmicroResistors0402:R_1k_0402")
		(at 68.58 267.97 270)
		(mirror x)
		(unit 1)
		(exclude_from_sim no)
		(in_bom yes)
		(on_board yes)
		(dnp no)
		(property "Reference" "R106"
			(at 66.675 264.1599 90)
			(effects
				(font
					(size 1.27 1.27)
				)
				(justify right)
			)
		)
		(property "Value" "R_1k_0402"
			(at 55.88 247.65 0)
			(effects
				(font
					(size 1.27 1.27)
					(thickness 0.15)
				)
				(justify left bottom)
				(hide yes)
			)
		)
		(property "Footprint" "antmicro-footprints:R_0402_1005Metric"
			(at 53.34 247.65 0)
			(effects
				(font
					(size 1.27 1.27)
					(thickness 0.15)
				)
				(justify left bottom)
				(hide yes)
			)
		)
		(property "Datasheet" "https://www.bourns.com/docs/product-datasheets/cr.pdf"
			(at 50.8 247.65 0)
			(effects
				(font
					(size 1.27 1.27)
					(thickness 0.15)
				)
				(justify left bottom)
				(hide yes)
			)
		)
		(property "Description" ""
			(at 68.58 267.97 0)
			(effects
				(font
					(size 1.27 1.27)
				)
			)
		)
		(property "Manufacturer" "Bourns"
			(at 45.72 247.65 0)
			(effects
				(font
					(size 1.27 1.27)
					(thickness 0.15)
				)
				(justify left bottom)
				(hide yes)
			)
		)
		(property "MPN" "CR0402-FX-1001GLF"
			(at 48.26 247.65 0)
			(effects
				(font
					(size 1.27 1.27)
					(thickness 0.15)
				)
				(justify left bottom)
				(hide yes)
			)
		)
		(property "Val" "1k"
			(at 66.675 266.6999 90)
			(effects
				(font
					(size 1.27 1.27)
					(thickness 0.15)
				)
				(justify right)
			)
		)
		(property "License" "Apache-2.0"
			(at 43.18 247.65 0)
			(effects
				(font
					(size 1.27 1.27)
					(thickness 0.15)
				)
				(justify left bottom)
				(hide yes)
			)
		)
		(property "Author" "Antmicro"
			(at 40.64 247.65 0)
			(effects
				(font
					(size 1.27 1.27)
					(thickness 0.15)
				)
				(justify left bottom)
				(hide yes)
			)
		)
		(property "Tolerance" "1%"
			(at 58.42 247.65 0)
			(effects
				(font
					(size 1.27 1.27)
				)
				(justify left bottom)
				(hide yes)
			)
		)
		(pin "1"
		)
		(pin "2"
		)
		(instances
			(project "k410t-devboard"
				(path ""
					(reference "R106")
					(unit 1)
				)
			)
		)
	)
	(symbol
		(lib_id "antmicropower:GND")
		(at 120.65 43.18 0)
		(mirror y)
		(unit 1)
		(exclude_from_sim no)
		(in_bom yes)
		(on_board yes)
		(dnp no)
		(property "Reference" "#PWR0160"
			(at 120.65 49.53 0)
			(effects
				(font
					(size 1.27 1.27)
				)
				(hide yes)
			)
		)
		(property "Value" "GND"
			(at 120.65 46.99 0)
			(effects
				(font
					(size 1.27 1.27)
				)
			)
		)
		(property "Footprint" ""
			(at 111.76 50.8 0)
			(effects
				(font
					(size 1.27 1.27)
					(thickness 0.15)
				)
				(justify left bottom)
				(hide yes)
			)
		)
		(property "Datasheet" ""
			(at 111.76 55.88 0)
			(effects
				(font
					(size 1.27 1.27)
					(thickness 0.15)
				)
				(justify left bottom)
				(hide yes)
			)
		)
		(property "Description" ""
			(at 120.65 43.18 0)
			(effects
				(font
					(size 1.27 1.27)
				)
			)
		)
		(property "Author" "Antmicro"
			(at 111.76 50.8 0)
			(effects
				(font
					(size 1.27 1.27)
					(thickness 0.15)
				)
				(justify left bottom)
				(hide yes)
			)
		)
		(property "License" "Apache-2.0"
			(at 111.76 53.34 0)
			(effects
				(font
					(size 1.27 1.27)
					(thickness 0.15)
				)
				(justify left bottom)
				(hide yes)
			)
		)
		(pin "1"
		)
		(instances
			(project "k410t-devboard"
				(path ""
					(reference "#PWR0160")
					(unit 1)
				)
			)
		)
	)
	(symbol
		(lib_id "antmicropower:GND")
		(at 115.57 184.15 0)
		(unit 1)
		(exclude_from_sim no)
		(in_bom yes)
		(on_board yes)
		(dnp no)
		(property "Reference" "#PWR0155"
			(at 115.57 190.5 0)
			(effects
				(font
					(size 1.27 1.27)
				)
				(hide yes)
			)
		)
		(property "Value" "GND"
			(at 115.57 187.96 0)
			(effects
				(font
					(size 1.27 1.27)
				)
			)
		)
		(property "Footprint" ""
			(at 124.46 191.77 0)
			(effects
				(font
					(size 1.27 1.27)
					(thickness 0.15)
				)
				(justify left bottom)
				(hide yes)
			)
		)
		(property "Datasheet" ""
			(at 124.46 196.85 0)
			(effects
				(font
					(size 1.27 1.27)
					(thickness 0.15)
				)
				(justify left bottom)
				(hide yes)
			)
		)
		(property "Description" ""
			(at 115.57 184.15 0)
			(effects
				(font
					(size 1.27 1.27)
				)
			)
		)
		(property "Author" "Antmicro"
			(at 124.46 191.77 0)
			(effects
				(font
					(size 1.27 1.27)
					(thickness 0.15)
				)
				(justify left bottom)
				(hide yes)
			)
		)
		(property "License" "Apache-2.0"
			(at 124.46 194.31 0)
			(effects
				(font
					(size 1.27 1.27)
					(thickness 0.15)
				)
				(justify left bottom)
				(hide yes)
			)
		)
		(pin "1"
		)
		(instances
			(project "k410t-devboard"
				(path ""
					(reference "#PWR0155")
					(unit 1)
				)
			)
		)
	)
	(symbol
		(lib_id "antmicroResistors0402:R_100R_0402")
		(at 87.63 35.56 180)
		(unit 1)
		(exclude_from_sim no)
		(in_bom yes)
		(on_board yes)
		(dnp no)
		(property "Reference" "R114"
			(at 90.17 34.29 0)
			(effects
				(font
					(size 1.27 1.27)
				)
			)
		)
		(property "Value" "R_100R_0402"
			(at 67.31 22.86 0)
			(effects
				(font
					(size 1.27 1.27)
					(thickness 0.15)
				)
				(justify left bottom)
				(hide yes)
			)
		)
		(property "Footprint" "antmicro-footprints:R_0402_1005Metric"
			(at 67.31 20.32 0)
			(effects
				(font
					(size 1.27 1.27)
					(thickness 0.15)
				)
				(justify left bottom)
				(hide yes)
			)
		)
		(property "Datasheet" "https://www.bourns.com/docs/product-datasheets/cr.pdf"
			(at 67.31 17.78 0)
			(effects
				(font
					(size 1.27 1.27)
					(thickness 0.15)
				)
				(justify left bottom)
				(hide yes)
			)
		)
		(property "Description" ""
			(at 87.63 35.56 0)
			(effects
				(font
					(size 1.27 1.27)
				)
			)
		)
		(property "Manufacturer" "Bourns"
			(at 67.31 12.7 0)
			(effects
				(font
					(size 1.27 1.27)
					(thickness 0.15)
				)
				(justify left bottom)
				(hide yes)
			)
		)
		(property "MPN" "CR0402-FX-1000GLF"
			(at 67.31 15.24 0)
			(effects
				(font
					(size 1.27 1.27)
					(thickness 0.15)
				)
				(justify left bottom)
				(hide yes)
			)
		)
		(property "Val" "100R"
			(at 80.01 34.29 0)
			(effects
				(font
					(size 1.27 1.27)
					(thickness 0.15)
				)
			)
		)
		(property "License" "Apache-2.0"
			(at 67.31 10.16 0)
			(effects
				(font
					(size 1.27 1.27)
					(thickness 0.15)
				)
				(justify left bottom)
				(hide yes)
			)
		)
		(property "Author" "Antmicro"
			(at 67.31 7.62 0)
			(effects
				(font
					(size 1.27 1.27)
					(thickness 0.15)
				)
				(justify left bottom)
				(hide yes)
			)
		)
		(property "Tolerance" "1%"
			(at 67.31 25.4 0)
			(effects
				(font
					(size 1.27 1.27)
				)
				(justify left bottom)
				(hide yes)
			)
		)
		(pin "1"
		)
		(pin "2"
		)
		(instances
			(project "k410t-devboard"
				(path ""
					(reference "R114")
					(unit 1)
				)
			)
		)
	)
	(symbol
		(lib_id "antmicropower:+3.3V")
		(at 132.08 170.18 0)
		(unit 1)
		(exclude_from_sim no)
		(in_bom yes)
		(on_board yes)
		(dnp no)
		(fields_autoplaced yes)
		(property "Reference" "#PWR0152"
			(at 132.08 173.99 0)
			(effects
				(font
					(size 1.27 1.27)
				)
				(hide yes)
			)
		)
		(property "Value" "+3V3"
			(at 132.08 166.624 0)
			(effects
				(font
					(size 1.27 1.27)
				)
			)
		)
		(property "Footprint" ""
			(at 132.08 170.18 0)
			(effects
				(font
					(size 1.27 1.27)
				)
				(hide yes)
			)
		)
		(property "Datasheet" ""
			(at 132.08 170.18 0)
			(effects
				(font
					(size 1.27 1.27)
				)
				(hide yes)
			)
		)
		(property "Description" ""
			(at 132.08 170.18 0)
			(effects
				(font
					(size 1.27 1.27)
				)
			)
		)
		(pin "1"
		)
		(instances
			(project "k410t-devboard"
				(path ""
					(reference "#PWR0152")
					(unit 1)
				)
			)
		)
	)
	(symbol
		(lib_id "antmicropower:GND")
		(at 295.91 279.4 0)
		(unit 1)
		(exclude_from_sim no)
		(in_bom yes)
		(on_board yes)
		(dnp no)
		(property "Reference" "#PWR0186"
			(at 295.91 285.75 0)
			(effects
				(font
					(size 1.27 1.27)
				)
				(hide yes)
			)
		)
		(property "Value" "GND"
			(at 295.91 283.21 0)
			(effects
				(font
					(size 1.27 1.27)
				)
			)
		)
		(property "Footprint" ""
			(at 304.8 287.02 0)
			(effects
				(font
					(size 1.27 1.27)
					(thickness 0.15)
				)
				(justify left bottom)
				(hide yes)
			)
		)
		(property "Datasheet" ""
			(at 304.8 292.1 0)
			(effects
				(font
					(size 1.27 1.27)
					(thickness 0.15)
				)
				(justify left bottom)
				(hide yes)
			)
		)
		(property "Description" ""
			(at 295.91 279.4 0)
			(effects
				(font
					(size 1.27 1.27)
				)
			)
		)
		(property "Author" "Antmicro"
			(at 304.8 287.02 0)
			(effects
				(font
					(size 1.27 1.27)
					(thickness 0.15)
				)
				(justify left bottom)
				(hide yes)
			)
		)
		(property "License" "Apache-2.0"
			(at 304.8 289.56 0)
			(effects
				(font
					(size 1.27 1.27)
					(thickness 0.15)
				)
				(justify left bottom)
				(hide yes)
			)
		)
		(pin "1"
		)
		(instances
			(project "k410t-devboard"
				(path ""
					(reference "#PWR0186")
					(unit 1)
				)
			)
		)
	)
	(symbol
		(lib_id "antmicropower:GND")
		(at 354.33 121.92 0)
		(unit 1)
		(exclude_from_sim no)
		(in_bom yes)
		(on_board yes)
		(dnp no)
		(fields_autoplaced yes)
		(property "Reference" "#PWR0192"
			(at 354.33 128.27 0)
			(effects
				(font
					(size 1.27 1.27)
				)
				(hide yes)
			)
		)
		(property "Value" "GND"
			(at 354.33 126.365 0)
			(effects
				(font
					(size 1.27 1.27)
				)
			)
		)
		(property "Footprint" ""
			(at 363.22 129.54 0)
			(effects
				(font
					(size 1.27 1.27)
					(thickness 0.15)
				)
				(justify left bottom)
				(hide yes)
			)
		)
		(property "Datasheet" ""
			(at 363.22 134.62 0)
			(effects
				(font
					(size 1.27 1.27)
					(thickness 0.15)
				)
				(justify left bottom)
				(hide yes)
			)
		)
		(property "Description" ""
			(at 354.33 121.92 0)
			(effects
				(font
					(size 1.27 1.27)
				)
			)
		)
		(property "Author" "Antmicro"
			(at 363.22 129.54 0)
			(effects
				(font
					(size 1.27 1.27)
					(thickness 0.15)
				)
				(justify left bottom)
				(hide yes)
			)
		)
		(property "License" "Apache-2.0"
			(at 363.22 132.08 0)
			(effects
				(font
					(size 1.27 1.27)
					(thickness 0.15)
				)
				(justify left bottom)
				(hide yes)
			)
		)
		(pin "1"
		)
		(instances
			(project "k410t-devboard"
				(path ""
					(reference "#PWR0192")
					(unit 1)
				)
			)
		)
	)
	(symbol
		(lib_id "antmicroResistors0402:R_100k_0402")
		(at 190.5 163.83 0)
		(unit 1)
		(exclude_from_sim no)
		(in_bom yes)
		(on_board yes)
		(dnp no)
		(property "Reference" "R357"
			(at 193.04 158.75 0)
			(effects
				(font
					(size 1.27 1.27)
				)
			)
		)
		(property "Value" "R_100k_0402"
			(at 210.82 176.53 0)
			(effects
				(font
					(size 1.27 1.27)
					(thickness 0.15)
				)
				(justify left bottom)
				(hide yes)
			)
		)
		(property "Footprint" "antmicro-footprints:R_0402_1005Metric"
			(at 210.82 179.07 0)
			(effects
				(font
					(size 1.27 1.27)
					(thickness 0.15)
				)
				(justify left bottom)
				(hide yes)
			)
		)
		(property "Datasheet" "https://www.bourns.com/docs/product-datasheets/cr.pdf"
			(at 210.82 181.61 0)
			(effects
				(font
					(size 1.27 1.27)
					(thickness 0.15)
				)
				(justify left bottom)
				(hide yes)
			)
		)
		(property "Description" ""
			(at 190.5 163.83 0)
			(effects
				(font
					(size 1.27 1.27)
				)
			)
		)
		(property "Manufacturer" "Bourns"
			(at 210.82 186.69 0)
			(effects
				(font
					(size 1.27 1.27)
					(thickness 0.15)
				)
				(justify left bottom)
				(hide yes)
			)
		)
		(property "MPN" "CR0402-FX-1003GLF"
			(at 210.82 184.15 0)
			(effects
				(font
					(size 1.27 1.27)
					(thickness 0.15)
				)
				(justify left bottom)
				(hide yes)
			)
		)
		(property "Val" "100k"
			(at 193.04 161.29 0)
			(effects
				(font
					(size 1.27 1.27)
					(thickness 0.15)
				)
			)
		)
		(property "License" "Apache-2.0"
			(at 210.82 189.23 0)
			(effects
				(font
					(size 1.27 1.27)
					(thickness 0.15)
				)
				(justify left bottom)
				(hide yes)
			)
		)
		(property "Author" "Antmicro"
			(at 210.82 191.77 0)
			(effects
				(font
					(size 1.27 1.27)
					(thickness 0.15)
				)
				(justify left bottom)
				(hide yes)
			)
		)
		(property "Tolerance" "1%"
			(at 210.82 173.99 0)
			(effects
				(font
					(size 1.27 1.27)
				)
				(justify left bottom)
				(hide yes)
			)
		)
		(pin "1"
		)
		(pin "2"
		)
		(instances
			(project "k410t-devboard"
				(path ""
					(reference "R357")
					(unit 1)
				)
			)
		)
	)
	(symbol
		(lib_id "antmicroResistors0402:R_100R_0402")
		(at 140.97 38.1 180)
		(unit 1)
		(exclude_from_sim no)
		(in_bom yes)
		(on_board yes)
		(dnp no)
		(property "Reference" "R123"
			(at 143.51 36.83 0)
			(effects
				(font
					(size 1.27 1.27)
				)
			)
		)
		(property "Value" "R_100R_0402"
			(at 120.65 25.4 0)
			(effects
				(font
					(size 1.27 1.27)
					(thickness 0.15)
				)
				(justify left bottom)
				(hide yes)
			)
		)
		(property "Footprint" "antmicro-footprints:R_0402_1005Metric"
			(at 120.65 22.86 0)
			(effects
				(font
					(size 1.27 1.27)
					(thickness 0.15)
				)
				(justify left bottom)
				(hide yes)
			)
		)
		(property "Datasheet" "https://www.bourns.com/docs/product-datasheets/cr.pdf"
			(at 120.65 20.32 0)
			(effects
				(font
					(size 1.27 1.27)
					(thickness 0.15)
				)
				(justify left bottom)
				(hide yes)
			)
		)
		(property "Description" ""
			(at 140.97 38.1 0)
			(effects
				(font
					(size 1.27 1.27)
				)
			)
		)
		(property "Manufacturer" "Bourns"
			(at 120.65 15.24 0)
			(effects
				(font
					(size 1.27 1.27)
					(thickness 0.15)
				)
				(justify left bottom)
				(hide yes)
			)
		)
		(property "MPN" "CR0402-FX-1000GLF"
			(at 120.65 17.78 0)
			(effects
				(font
					(size 1.27 1.27)
					(thickness 0.15)
				)
				(justify left bottom)
				(hide yes)
			)
		)
		(property "Val" "100R"
			(at 133.35 36.83 0)
			(effects
				(font
					(size 1.27 1.27)
					(thickness 0.15)
				)
			)
		)
		(property "License" "Apache-2.0"
			(at 120.65 12.7 0)
			(effects
				(font
					(size 1.27 1.27)
					(thickness 0.15)
				)
				(justify left bottom)
				(hide yes)
			)
		)
		(property "Author" "Antmicro"
			(at 120.65 10.16 0)
			(effects
				(font
					(size 1.27 1.27)
					(thickness 0.15)
				)
				(justify left bottom)
				(hide yes)
			)
		)
		(property "Tolerance" "1%"
			(at 120.65 27.94 0)
			(effects
				(font
					(size 1.27 1.27)
				)
				(justify left bottom)
				(hide yes)
			)
		)
		(pin "1"
		)
		(pin "2"
		)
		(instances
			(project "k410t-devboard"
				(path ""
					(reference "R123")
					(unit 1)
				)
			)
		)
	)
	(symbol
		(lib_id "antmicropower:GND")
		(at 86.36 251.46 0)
		(unit 1)
		(exclude_from_sim no)
		(in_bom yes)
		(on_board yes)
		(dnp no)
		(fields_autoplaced yes)
		(property "Reference" "#PWR0137"
			(at 86.36 257.81 0)
			(effects
				(font
					(size 1.27 1.27)
				)
				(hide yes)
			)
		)
		(property "Value" "GND"
			(at 86.36 255.905 0)
			(effects
				(font
					(size 1.27 1.27)
				)
			)
		)
		(property "Footprint" ""
			(at 95.25 259.08 0)
			(effects
				(font
					(size 1.27 1.27)
					(thickness 0.15)
				)
				(justify left bottom)
				(hide yes)
			)
		)
		(property "Datasheet" ""
			(at 95.25 264.16 0)
			(effects
				(font
					(size 1.27 1.27)
					(thickness 0.15)
				)
				(justify left bottom)
				(hide yes)
			)
		)
		(property "Description" ""
			(at 86.36 251.46 0)
			(effects
				(font
					(size 1.27 1.27)
				)
			)
		)
		(property "Author" "Antmicro"
			(at 95.25 259.08 0)
			(effects
				(font
					(size 1.27 1.27)
					(thickness 0.15)
				)
				(justify left bottom)
				(hide yes)
			)
		)
		(property "License" "Apache-2.0"
			(at 95.25 261.62 0)
			(effects
				(font
					(size 1.27 1.27)
					(thickness 0.15)
				)
				(justify left bottom)
				(hide yes)
			)
		)
		(pin "1"
		)
		(instances
			(project "k410t-devboard"
				(path ""
					(reference "#PWR0137")
					(unit 1)
				)
			)
		)
	)
	(symbol
		(lib_id "antmicroTransistorsFETsMOSFETsSingle:BSS138PW")
		(at 96.52 181.61 90)
		(unit 1)
		(exclude_from_sim no)
		(in_bom yes)
		(on_board yes)
		(dnp no)
		(fields_autoplaced yes)
		(property "Reference" "Q9"
			(at 93.98 166.37 90)
			(effects
				(font
					(size 1.27 1.27)
				)
			)
		)
		(property "Value" "BSS138PW"
			(at 93.98 168.91 90)
			(effects
				(font
					(size 1.27 1.27)
					(thickness 0.15)
				)
			)
		)
		(property "Footprint" "antmicro-footprints:SC70-3"
			(at 107.95 158.75 0)
			(effects
				(font
					(size 1.27 1.27)
					(thickness 0.15)
				)
				(justify left bottom)
				(hide yes)
			)
		)
		(property "Datasheet" "https://assets.nexperia.com/documents/data-sheet/BSS138PW.pdf"
			(at 110.49 158.75 0)
			(effects
				(font
					(size 1.27 1.27)
					(thickness 0.15)
				)
				(justify left bottom)
				(hide yes)
			)
		)
		(property "Description" ""
			(at 96.52 181.61 0)
			(effects
				(font
					(size 1.27 1.27)
				)
			)
		)
		(property "MPN" "BSS138PW"
			(at 113.03 158.75 0)
			(effects
				(font
					(size 1.27 1.27)
					(thickness 0.15)
				)
				(justify left bottom)
				(hide yes)
			)
		)
		(property "Manufacturer" "Nexperia"
			(at 115.57 158.75 0)
			(effects
				(font
					(size 1.27 1.27)
					(thickness 0.15)
				)
				(justify left bottom)
				(hide yes)
			)
		)
		(property "Author" "Antmicro"
			(at 118.11 158.75 0)
			(effects
				(font
					(size 1.27 1.27)
					(thickness 0.15)
				)
				(justify left bottom)
				(hide yes)
			)
		)
		(property "License" "Apache-2.0"
			(at 120.65 158.75 0)
			(effects
				(font
					(size 1.27 1.27)
					(thickness 0.15)
				)
				(justify left bottom)
				(hide yes)
			)
		)
		(pin "1"
		)
		(pin "2"
		)
		(pin "3"
		)
		(instances
			(project "k410t-devboard"
				(path ""
					(reference "Q9")
					(unit 1)
				)
			)
		)
	)
	(symbol
		(lib_id "antmicropower:GND")
		(at 101.6 43.18 0)
		(unit 1)
		(exclude_from_sim no)
		(in_bom yes)
		(on_board yes)
		(dnp no)
		(property "Reference" "#PWR0139"
			(at 101.6 49.53 0)
			(effects
				(font
					(size 1.27 1.27)
				)
				(hide yes)
			)
		)
		(property "Value" "GND"
			(at 101.6 46.99 0)
			(effects
				(font
					(size 1.27 1.27)
				)
			)
		)
		(property "Footprint" ""
			(at 110.49 50.8 0)
			(effects
				(font
					(size 1.27 1.27)
					(thickness 0.15)
				)
				(justify left bottom)
				(hide yes)
			)
		)
		(property "Datasheet" ""
			(at 110.49 55.88 0)
			(effects
				(font
					(size 1.27 1.27)
					(thickness 0.15)
				)
				(justify left bottom)
				(hide yes)
			)
		)
		(property "Description" ""
			(at 101.6 43.18 0)
			(effects
				(font
					(size 1.27 1.27)
				)
			)
		)
		(property "Author" "Antmicro"
			(at 110.49 50.8 0)
			(effects
				(font
					(size 1.27 1.27)
					(thickness 0.15)
				)
				(justify left bottom)
				(hide yes)
			)
		)
		(property "License" "Apache-2.0"
			(at 110.49 53.34 0)
			(effects
				(font
					(size 1.27 1.27)
					(thickness 0.15)
				)
				(justify left bottom)
				(hide yes)
			)
		)
		(pin "1"
		)
		(instances
			(project "k410t-devboard"
				(path ""
					(reference "#PWR0139")
					(unit 1)
				)
			)
		)
	)
	(symbol
		(lib_id "antmicroResistors0402:R_100R_0402")
		(at 279.4 38.1 180)
		(unit 1)
		(exclude_from_sim no)
		(in_bom yes)
		(on_board yes)
		(dnp no)
		(property "Reference" "R135"
			(at 281.94 36.83 0)
			(effects
				(font
					(size 1.27 1.27)
				)
			)
		)
		(property "Value" "R_100R_0402"
			(at 259.08 25.4 0)
			(effects
				(font
					(size 1.27 1.27)
					(thickness 0.15)
				)
				(justify left bottom)
				(hide yes)
			)
		)
		(property "Footprint" "antmicro-footprints:R_0402_1005Metric"
			(at 259.08 22.86 0)
			(effects
				(font
					(size 1.27 1.27)
					(thickness 0.15)
				)
				(justify left bottom)
				(hide yes)
			)
		)
		(property "Datasheet" "https://www.bourns.com/docs/product-datasheets/cr.pdf"
			(at 259.08 20.32 0)
			(effects
				(font
					(size 1.27 1.27)
					(thickness 0.15)
				)
				(justify left bottom)
				(hide yes)
			)
		)
		(property "Description" ""
			(at 279.4 38.1 0)
			(effects
				(font
					(size 1.27 1.27)
				)
			)
		)
		(property "Manufacturer" "Bourns"
			(at 259.08 15.24 0)
			(effects
				(font
					(size 1.27 1.27)
					(thickness 0.15)
				)
				(justify left bottom)
				(hide yes)
			)
		)
		(property "MPN" "CR0402-FX-1000GLF"
			(at 259.08 17.78 0)
			(effects
				(font
					(size 1.27 1.27)
					(thickness 0.15)
				)
				(justify left bottom)
				(hide yes)
			)
		)
		(property "Val" "100R"
			(at 271.78 36.83 0)
			(effects
				(font
					(size 1.27 1.27)
					(thickness 0.15)
				)
			)
		)
		(property "License" "Apache-2.0"
			(at 259.08 12.7 0)
			(effects
				(font
					(size 1.27 1.27)
					(thickness 0.15)
				)
				(justify left bottom)
				(hide yes)
			)
		)
		(property "Author" "Antmicro"
			(at 259.08 10.16 0)
			(effects
				(font
					(size 1.27 1.27)
					(thickness 0.15)
				)
				(justify left bottom)
				(hide yes)
			)
		)
		(property "Tolerance" "1%"
			(at 259.08 27.94 0)
			(effects
				(font
					(size 1.27 1.27)
				)
				(justify left bottom)
				(hide yes)
			)
		)
		(pin "1"
		)
		(pin "2"
		)
		(instances
			(project "k410t-devboard"
				(path ""
					(reference "R135")
					(unit 1)
				)
			)
		)
	)
	(symbol
		(lib_id "antmicroResistors0402:R_100R_0402")
		(at 140.97 95.25 180)
		(unit 1)
		(exclude_from_sim no)
		(in_bom yes)
		(on_board yes)
		(dnp no)
		(property "Reference" "R127"
			(at 143.51 93.98 0)
			(effects
				(font
					(size 1.27 1.27)
				)
			)
		)
		(property "Value" "R_100R_0402"
			(at 120.65 82.55 0)
			(effects
				(font
					(size 1.27 1.27)
					(thickness 0.15)
				)
				(justify left bottom)
				(hide yes)
			)
		)
		(property "Footprint" "antmicro-footprints:R_0402_1005Metric"
			(at 120.65 80.01 0)
			(effects
				(font
					(size 1.27 1.27)
					(thickness 0.15)
				)
				(justify left bottom)
				(hide yes)
			)
		)
		(property "Datasheet" "https://www.bourns.com/docs/product-datasheets/cr.pdf"
			(at 120.65 77.47 0)
			(effects
				(font
					(size 1.27 1.27)
					(thickness 0.15)
				)
				(justify left bottom)
				(hide yes)
			)
		)
		(property "Description" ""
			(at 140.97 95.25 0)
			(effects
				(font
					(size 1.27 1.27)
				)
			)
		)
		(property "Manufacturer" "Bourns"
			(at 120.65 72.39 0)
			(effects
				(font
					(size 1.27 1.27)
					(thickness 0.15)
				)
				(justify left bottom)
				(hide yes)
			)
		)
		(property "MPN" "CR0402-FX-1000GLF"
			(at 120.65 74.93 0)
			(effects
				(font
					(size 1.27 1.27)
					(thickness 0.15)
				)
				(justify left bottom)
				(hide yes)
			)
		)
		(property "Val" "100R"
			(at 133.35 93.98 0)
			(effects
				(font
					(size 1.27 1.27)
					(thickness 0.15)
				)
			)
		)
		(property "License" "Apache-2.0"
			(at 120.65 69.85 0)
			(effects
				(font
					(size 1.27 1.27)
					(thickness 0.15)
				)
				(justify left bottom)
				(hide yes)
			)
		)
		(property "Author" "Antmicro"
			(at 120.65 67.31 0)
			(effects
				(font
					(size 1.27 1.27)
					(thickness 0.15)
				)
				(justify left bottom)
				(hide yes)
			)
		)
		(property "Tolerance" "1%"
			(at 120.65 85.09 0)
			(effects
				(font
					(size 1.27 1.27)
				)
				(justify left bottom)
				(hide yes)
			)
		)
		(pin "1"
		)
		(pin "2"
		)
		(instances
			(project "k410t-devboard"
				(path ""
					(reference "R127")
					(unit 1)
				)
			)
		)
	)
	(symbol
		(lib_id "antmicroGenericPinHeaders:PinHeader_2x17_P1.27mm_SMD_Shrouded")
		(at 353.06 160.02 0)
		(unit 1)
		(exclude_from_sim no)
		(in_bom yes)
		(on_board yes)
		(dnp no)
		(property "Reference" "J11"
			(at 358.14 152.4 0)
			(effects
				(font
					(size 1.27 1.27)
				)
			)
		)
		(property "Value" "PinHeader_2x17_P1.27mm_SMD_Shrouded"
			(at 358.14 154.94 0)
			(effects
				(font
					(size 1.27 1.27)
					(thickness 0.15)
				)
			)
		)
		(property "Footprint" "antmicro-footprints:PinHeader_2x17_P1.27mm_SMD_Shrouded"
			(at 378.46 171.45 0)
			(effects
				(font
					(size 1.27 1.27)
					(thickness 0.15)
				)
				(justify left bottom)
				(hide yes)
			)
		)
		(property "Datasheet" "https://www.we-online.com/catalog/datasheet/62703420621.pdf"
			(at 378.46 173.99 0)
			(effects
				(font
					(size 1.27 1.27)
					(thickness 0.15)
				)
				(justify left bottom)
				(hide yes)
			)
		)
		(property "Description" ""
			(at 353.06 160.02 0)
			(effects
				(font
					(size 1.27 1.27)
				)
			)
		)
		(property "MPN" "62703420621"
			(at 378.46 176.53 0)
			(effects
				(font
					(size 1.27 1.27)
					(thickness 0.15)
				)
				(justify left bottom)
				(hide yes)
			)
		)
		(property "Manufacturer" "Würth Elektronik"
			(at 378.46 179.07 0)
			(effects
				(font
					(size 1.27 1.27)
					(thickness 0.15)
				)
				(justify left bottom)
				(hide yes)
			)
		)
		(property "Author" "Antmicro"
			(at 378.46 181.61 0)
			(effects
				(font
					(size 1.27 1.27)
					(thickness 0.15)
				)
				(justify left bottom)
				(hide yes)
			)
		)
		(property "License" "Apache-2.0"
			(at 378.46 184.15 0)
			(effects
				(font
					(size 1.27 1.27)
					(thickness 0.15)
				)
				(justify left bottom)
				(hide yes)
			)
		)
		(pin "1"
		)
		(pin "10"
		)
		(pin "11"
		)
		(pin "12"
		)
		(pin "13"
		)
		(pin "14"
		)
		(pin "15"
		)
		(pin "16"
		)
		(pin "17"
		)
		(pin "18"
		)
		(pin "19"
		)
		(pin "2"
		)
		(pin "20"
		)
		(pin "21"
		)
		(pin "22"
		)
		(pin "23"
		)
		(pin "24"
		)
		(pin "25"
		)
		(pin "26"
		)
		(pin "27"
		)
		(pin "28"
		)
		(pin "29"
		)
		(pin "3"
		)
		(pin "30"
		)
		(pin "31"
		)
		(pin "32"
		)
		(pin "33"
		)
		(pin "34"
		)
		(pin "4"
		)
		(pin "5"
		)
		(pin "6"
		)
		(pin "7"
		)
		(pin "8"
		)
		(pin "9"
		)
		(instances
			(project "k410t-devboard"
				(path ""
					(reference "J11")
					(unit 1)
				)
			)
		)
	)
	(symbol
		(lib_id "antmicropower:GND")
		(at 306.07 54.61 0)
		(unit 1)
		(exclude_from_sim no)
		(in_bom yes)
		(on_board yes)
		(dnp no)
		(property "Reference" "#PWR0187"
			(at 306.07 60.96 0)
			(effects
				(font
					(size 1.27 1.27)
				)
				(hide yes)
			)
		)
		(property "Value" "GND"
			(at 306.07 58.42 0)
			(effects
				(font
					(size 1.27 1.27)
				)
			)
		)
		(property "Footprint" ""
			(at 314.96 62.23 0)
			(effects
				(font
					(size 1.27 1.27)
					(thickness 0.15)
				)
				(justify left bottom)
				(hide yes)
			)
		)
		(property "Datasheet" ""
			(at 314.96 67.31 0)
			(effects
				(font
					(size 1.27 1.27)
					(thickness 0.15)
				)
				(justify left bottom)
				(hide yes)
			)
		)
		(property "Description" ""
			(at 306.07 54.61 0)
			(effects
				(font
					(size 1.27 1.27)
				)
			)
		)
		(property "Author" "Antmicro"
			(at 314.96 62.23 0)
			(effects
				(font
					(size 1.27 1.27)
					(thickness 0.15)
				)
				(justify left bottom)
				(hide yes)
			)
		)
		(property "License" "Apache-2.0"
			(at 314.96 64.77 0)
			(effects
				(font
					(size 1.27 1.27)
					(thickness 0.15)
				)
				(justify left bottom)
				(hide yes)
			)
		)
		(pin "1"
		)
		(instances
			(project "k410t-devboard"
				(path ""
					(reference "#PWR0187")
					(unit 1)
				)
			)
		)
	)
	(symbol
		(lib_id "antmicroGenericPinSockets:PinSocket_2x6_P2.54mm_Drill1.04mm_Horizontal")
		(at 106.68 30.48 0)
		(unit 1)
		(exclude_from_sim no)
		(in_bom yes)
		(on_board yes)
		(dnp no)
		(fields_autoplaced yes)
		(property "Reference" "J5"
			(at 111.76 21.59 0)
			(effects
				(font
					(size 1.27 1.27)
				)
			)
		)
		(property "Value" "PinSocket_2x6_P2.54mm_Drill1.04mm_Horizontal"
			(at 111.76 24.765 0)
			(effects
				(font
					(size 1.27 1.27)
					(thickness 0.15)
				)
				(hide yes)
			)
		)
		(property "Footprint" "antmicro-footprints:PinSocket_2x6_P2.54mm_Drill1.04mm_Horizontal"
			(at 125.73 35.56 0)
			(effects
				(font
					(size 1.27 1.27)
					(thickness 0.15)
				)
				(justify left bottom)
				(hide yes)
			)
		)
		(property "Datasheet" "https://suddendocs.samtec.com/prints/ssw-1xx-xx-xxx-x-xx-xxx-xx-mkt.pdf"
			(at 125.73 38.1 0)
			(effects
				(font
					(size 1.27 1.27)
					(thickness 0.15)
				)
				(justify left bottom)
				(hide yes)
			)
		)
		(property "Description" ""
			(at 106.68 30.48 0)
			(effects
				(font
					(size 1.27 1.27)
				)
			)
		)
		(property "Manufacturer" "Samtec"
			(at 125.73 40.64 0)
			(effects
				(font
					(size 1.27 1.27)
					(thickness 0.15)
				)
				(justify left bottom)
				(hide yes)
			)
		)
		(property "MPN" "SSW-106-02-G-D-RA"
			(at 111.76 24.13 0)
			(effects
				(font
					(size 1.27 1.27)
					(thickness 0.15)
				)
			)
		)
		(property "Author" "Antmicro"
			(at 125.73 45.72 0)
			(effects
				(font
					(size 1.27 1.27)
					(thickness 0.15)
				)
				(justify left bottom)
				(hide yes)
			)
		)
		(property "License" "Apache-2.0"
			(at 125.73 48.26 0)
			(effects
				(font
					(size 1.27 1.27)
					(thickness 0.15)
				)
				(justify left bottom)
				(hide yes)
			)
		)
		(pin "1"
		)
		(pin "10"
		)
		(pin "11"
		)
		(pin "12"
		)
		(pin "2"
		)
		(pin "3"
		)
		(pin "4"
		)
		(pin "5"
		)
		(pin "6"
		)
		(pin "7"
		)
		(pin "8"
		)
		(pin "9"
		)
		(instances
			(project "k410t-devboard"
				(path ""
					(reference "J5")
					(unit 1)
				)
			)
		)
	)
	(symbol
		(lib_id "antmicropower:GND")
		(at 101.6 100.33 0)
		(unit 1)
		(exclude_from_sim no)
		(in_bom yes)
		(on_board yes)
		(dnp no)
		(property "Reference" "#PWR0140"
			(at 101.6 106.68 0)
			(effects
				(font
					(size 1.27 1.27)
				)
				(hide yes)
			)
		)
		(property "Value" "GND"
			(at 101.6 104.14 0)
			(effects
				(font
					(size 1.27 1.27)
				)
			)
		)
		(property "Footprint" ""
			(at 110.49 107.95 0)
			(effects
				(font
					(size 1.27 1.27)
					(thickness 0.15)
				)
				(justify left bottom)
				(hide yes)
			)
		)
		(property "Datasheet" ""
			(at 110.49 113.03 0)
			(effects
				(font
					(size 1.27 1.27)
					(thickness 0.15)
				)
				(justify left bottom)
				(hide yes)
			)
		)
		(property "Description" ""
			(at 101.6 100.33 0)
			(effects
				(font
					(size 1.27 1.27)
				)
			)
		)
		(property "Author" "Antmicro"
			(at 110.49 107.95 0)
			(effects
				(font
					(size 1.27 1.27)
					(thickness 0.15)
				)
				(justify left bottom)
				(hide yes)
			)
		)
		(property "License" "Apache-2.0"
			(at 110.49 110.49 0)
			(effects
				(font
					(size 1.27 1.27)
					(thickness 0.15)
				)
				(justify left bottom)
				(hide yes)
			)
		)
		(pin "1"
		)
		(instances
			(project "k410t-devboard"
				(path ""
					(reference "#PWR0140")
					(unit 1)
				)
			)
		)
	)
	(symbol
		(lib_id "antmicroResistors0402:R_1k_0402")
		(at 54.61 193.04 0)
		(unit 1)
		(exclude_from_sim no)
		(in_bom yes)
		(on_board yes)
		(dnp no)
		(property "Reference" "R109"
			(at 57.15 187.96 0)
			(effects
				(font
					(size 1.27 1.27)
				)
			)
		)
		(property "Value" "R_1k_0402"
			(at 74.93 205.74 0)
			(effects
				(font
					(size 1.27 1.27)
					(thickness 0.15)
				)
				(justify left bottom)
				(hide yes)
			)
		)
		(property "Footprint" "antmicro-footprints:R_0402_1005Metric"
			(at 74.93 208.28 0)
			(effects
				(font
					(size 1.27 1.27)
					(thickness 0.15)
				)
				(justify left bottom)
				(hide yes)
			)
		)
		(property "Datasheet" "https://www.bourns.com/docs/product-datasheets/cr.pdf"
			(at 74.93 210.82 0)
			(effects
				(font
					(size 1.27 1.27)
					(thickness 0.15)
				)
				(justify left bottom)
				(hide yes)
			)
		)
		(property "Description" ""
			(at 54.61 193.04 0)
			(effects
				(font
					(size 1.27 1.27)
				)
			)
		)
		(property "Manufacturer" "Bourns"
			(at 74.93 215.9 0)
			(effects
				(font
					(size 1.27 1.27)
					(thickness 0.15)
				)
				(justify left bottom)
				(hide yes)
			)
		)
		(property "MPN" "CR0402-FX-1001GLF"
			(at 74.93 213.36 0)
			(effects
				(font
					(size 1.27 1.27)
					(thickness 0.15)
				)
				(justify left bottom)
				(hide yes)
			)
		)
		(property "Val" "1k"
			(at 57.15 190.5 0)
			(effects
				(font
					(size 1.27 1.27)
					(thickness 0.15)
				)
			)
		)
		(property "License" "Apache-2.0"
			(at 74.93 218.44 0)
			(effects
				(font
					(size 1.27 1.27)
					(thickness 0.15)
				)
				(justify left bottom)
				(hide yes)
			)
		)
		(property "Author" "Antmicro"
			(at 74.93 220.98 0)
			(effects
				(font
					(size 1.27 1.27)
					(thickness 0.15)
				)
				(justify left bottom)
				(hide yes)
			)
		)
		(property "Tolerance" "1%"
			(at 74.93 203.2 0)
			(effects
				(font
					(size 1.27 1.27)
				)
				(justify left bottom)
				(hide yes)
			)
		)
		(pin "1"
		)
		(pin "2"
		)
		(instances
			(project "k410t-devboard"
				(path ""
					(reference "R109")
					(unit 1)
				)
			)
		)
	)
	(symbol
		(lib_id "antmicroCapacitors0402:C_1u_0402")
		(at 111.76 59.69 90)
		(unit 1)
		(exclude_from_sim no)
		(in_bom yes)
		(on_board yes)
		(dnp no)
		(property "Reference" "C214"
			(at 113.665 55.88 90)
			(effects
				(font
					(size 1.27 1.27)
				)
				(justify right)
			)
		)
		(property "Value" "C_1u_0402"
			(at 121.92 39.37 0)
			(effects
				(font
					(size 1.27 1.27)
					(thickness 0.15)
				)
				(justify left bottom)
				(hide yes)
			)
		)
		(property "Footprint" "antmicro-footprints:C_0402_1005Metric"
			(at 124.46 39.37 0)
			(effects
				(font
					(size 1.27 1.27)
					(thickness 0.15)
				)
				(justify left bottom)
				(hide yes)
			)
		)
		(property "Datasheet" "https://product.tdk.com/en/search/capacitor/ceramic/mlcc/info?part_no=C1005X6S1A105K050BC"
			(at 127 39.37 0)
			(effects
				(font
					(size 1.27 1.27)
					(thickness 0.15)
				)
				(justify left bottom)
				(hide yes)
			)
		)
		(property "Description" ""
			(at 111.76 59.69 0)
			(effects
				(font
					(size 1.27 1.27)
				)
			)
		)
		(property "Manufacturer" "TDK"
			(at 132.08 39.37 0)
			(effects
				(font
					(size 1.27 1.27)
					(thickness 0.15)
				)
				(justify left bottom)
				(hide yes)
			)
		)
		(property "MPN" "C1005X6S1A105K050BC"
			(at 129.54 39.37 0)
			(effects
				(font
					(size 1.27 1.27)
					(thickness 0.15)
				)
				(justify left bottom)
				(hide yes)
			)
		)
		(property "Val" "1u"
			(at 113.665 58.42 90)
			(effects
				(font
					(size 1.27 1.27)
					(thickness 0.15)
				)
				(justify right)
			)
		)
		(property "License" "Apache-2.0"
			(at 134.62 39.37 0)
			(effects
				(font
					(size 1.27 1.27)
					(thickness 0.15)
				)
				(justify left bottom)
				(hide yes)
			)
		)
		(property "Author" "Antmicro"
			(at 137.16 39.37 0)
			(effects
				(font
					(size 1.27 1.27)
					(thickness 0.15)
				)
				(justify left bottom)
				(hide yes)
			)
		)
		(property "Voltage" ""
			(at 139.7 39.37 0)
			(effects
				(font
					(size 1.27 1.27)
				)
				(justify left bottom)
				(hide yes)
			)
		)
		(property "Dielectric" ""
			(at 142.24 39.37 0)
			(effects
				(font
					(size 1.27 1.27)
				)
				(justify left bottom)
				(hide yes)
			)
		)
		(pin "1"
		)
		(pin "2"
		)
		(instances
			(project "k410t-devboard"
				(path ""
					(reference "C214")
					(unit 1)
				)
			)
		)
	)
	(symbol
		(lib_id "antmicropower:+3.3V")
		(at 49.53 207.01 0)
		(unit 1)
		(exclude_from_sim no)
		(in_bom yes)
		(on_board yes)
		(dnp no)
		(fields_autoplaced yes)
		(property "Reference" "#PWR0131"
			(at 49.53 210.82 0)
			(effects
				(font
					(size 1.27 1.27)
				)
				(hide yes)
			)
		)
		(property "Value" "+3V3"
			(at 49.53 203.454 0)
			(effects
				(font
					(size 1.27 1.27)
				)
			)
		)
		(property "Footprint" ""
			(at 49.53 207.01 0)
			(effects
				(font
					(size 1.27 1.27)
				)
				(hide yes)
			)
		)
		(property "Datasheet" ""
			(at 49.53 207.01 0)
			(effects
				(font
					(size 1.27 1.27)
				)
				(hide yes)
			)
		)
		(property "Description" ""
			(at 49.53 207.01 0)
			(effects
				(font
					(size 1.27 1.27)
				)
			)
		)
		(pin "1"
		)
		(instances
			(project "k410t-devboard"
				(path ""
					(reference "#PWR0131")
					(unit 1)
				)
			)
		)
	)
	(symbol
		(lib_id "antmicroSlideSwitches:SW_CVS-08TB")
		(at 279.4 257.81 0)
		(unit 1)
		(exclude_from_sim no)
		(in_bom yes)
		(on_board yes)
		(dnp no)
		(fields_autoplaced yes)
		(property "Reference" "SW2"
			(at 285.7517 250.19 0)
			(effects
				(font
					(size 1.27 1.27)
				)
			)
		)
		(property "Value" "SW_CVS-08TB"
			(at 285.7517 252.73 0)
			(effects
				(font
					(size 1.27 1.27)
					(thickness 0.15)
				)
				(hide yes)
			)
		)
		(property "Footprint" "antmicro-footprints:SW_DIP_SPSTx08_Slide_Copal_CVS-08xB_W5.9mm_P1mm"
			(at 306.07 265.43 0)
			(effects
				(font
					(size 1.27 1.27)
					(thickness 0.15)
				)
				(justify left bottom)
				(hide yes)
			)
		)
		(property "Datasheet" "https://www.mouser.com/datasheet/2/972/cvs-1827291.pdf"
			(at 306.07 267.97 0)
			(effects
				(font
					(size 1.27 1.27)
					(thickness 0.15)
				)
				(justify left bottom)
				(hide yes)
			)
		)
		(property "Description" ""
			(at 279.4 257.81 0)
			(effects
				(font
					(size 1.27 1.27)
				)
			)
		)
		(property "MPN" "CVS-08TB"
			(at 285.7517 252.73 0)
			(effects
				(font
					(size 1.27 1.27)
					(thickness 0.15)
				)
			)
		)
		(property "Manufacturer" "Nidec Components"
			(at 306.07 273.05 0)
			(effects
				(font
					(size 1.27 1.27)
					(thickness 0.15)
				)
				(justify left bottom)
				(hide yes)
			)
		)
		(property "Author" "Antmicro"
			(at 306.07 275.59 0)
			(effects
				(font
					(size 1.27 1.27)
					(thickness 0.15)
				)
				(justify left bottom)
				(hide yes)
			)
		)
		(property "License" "Apache-2.0"
			(at 306.07 278.13 0)
			(effects
				(font
					(size 1.27 1.27)
					(thickness 0.15)
				)
				(justify left bottom)
				(hide yes)
			)
		)
		(pin "1"
		)
		(pin "10"
		)
		(pin "11"
		)
		(pin "12"
		)
		(pin "13"
		)
		(pin "14"
		)
		(pin "15"
		)
		(pin "16"
		)
		(pin "17"
		)
		(pin "2"
		)
		(pin "3"
		)
		(pin "4"
		)
		(pin "5"
		)
		(pin "6"
		)
		(pin "7"
		)
		(pin "8"
		)
		(pin "9"
		)
		(instances
			(project "k410t-devboard"
				(path ""
					(reference "SW2")
					(unit 1)
				)
			)
		)
	)
	(symbol
		(lib_id "antmicroTransistorsFETsMOSFETsSingle:IRLML6344TRPBF")
		(at 116.84 279.4 90)
		(unit 1)
		(exclude_from_sim no)
		(in_bom yes)
		(on_board yes)
		(dnp no)
		(property "Reference" "Q12"
			(at 114.3 264.16 90)
			(effects
				(font
					(size 1.27 1.27)
				)
			)
		)
		(property "Value" "IRLML6344TRPBF"
			(at 114.3 266.7 90)
			(effects
				(font
					(size 1.27 1.27)
					(thickness 0.15)
				)
				(hide yes)
			)
		)
		(property "Footprint" "antmicro-footprints:SOT-23-3"
			(at 128.27 256.54 0)
			(effects
				(font
					(size 1.27 1.27)
					(thickness 0.15)
				)
				(justify left bottom)
				(hide yes)
			)
		)
		(property "Datasheet" "https://www.infineon.com/dgdl/irlml6344pbf.pdf?fileId=5546d462533600a4015356689c44262c"
			(at 130.81 256.54 0)
			(effects
				(font
					(size 1.27 1.27)
					(thickness 0.15)
				)
				(justify left bottom)
				(hide yes)
			)
		)
		(property "Description" ""
			(at 116.84 279.4 0)
			(effects
				(font
					(size 1.27 1.27)
				)
			)
		)
		(property "MPN" "IRLML6344TRPBF"
			(at 114.3 266.7 90)
			(effects
				(font
					(size 1.27 1.27)
					(thickness 0.15)
				)
			)
		)
		(property "Manufacturer" "Infineon"
			(at 135.89 256.54 0)
			(effects
				(font
					(size 1.27 1.27)
					(thickness 0.15)
				)
				(justify left bottom)
				(hide yes)
			)
		)
		(property "Author" "Antmicro"
			(at 138.43 256.54 0)
			(effects
				(font
					(size 1.27 1.27)
					(thickness 0.15)
				)
				(justify left bottom)
				(hide yes)
			)
		)
		(property "License" "Apache-2.0"
			(at 140.97 256.54 0)
			(effects
				(font
					(size 1.27 1.27)
					(thickness 0.15)
				)
				(justify left bottom)
				(hide yes)
			)
		)
		(pin "1"
		)
		(pin "2"
		)
		(pin "3"
		)
		(instances
			(project "k410t-devboard"
				(path ""
					(reference "Q12")
					(unit 1)
				)
			)
		)
	)
	(symbol
		(lib_id "antmicroResistors0402:R_100R_0402")
		(at 279.4 35.56 180)
		(unit 1)
		(exclude_from_sim no)
		(in_bom yes)
		(on_board yes)
		(dnp no)
		(property "Reference" "R134"
			(at 281.94 34.29 0)
			(effects
				(font
					(size 1.27 1.27)
				)
			)
		)
		(property "Value" "R_100R_0402"
			(at 259.08 22.86 0)
			(effects
				(font
					(size 1.27 1.27)
					(thickness 0.15)
				)
				(justify left bottom)
				(hide yes)
			)
		)
		(property "Footprint" "antmicro-footprints:R_0402_1005Metric"
			(at 259.08 20.32 0)
			(effects
				(font
					(size 1.27 1.27)
					(thickness 0.15)
				)
				(justify left bottom)
				(hide yes)
			)
		)
		(property "Datasheet" "https://www.bourns.com/docs/product-datasheets/cr.pdf"
			(at 259.08 17.78 0)
			(effects
				(font
					(size 1.27 1.27)
					(thickness 0.15)
				)
				(justify left bottom)
				(hide yes)
			)
		)
		(property "Description" ""
			(at 279.4 35.56 0)
			(effects
				(font
					(size 1.27 1.27)
				)
			)
		)
		(property "Manufacturer" "Bourns"
			(at 259.08 12.7 0)
			(effects
				(font
					(size 1.27 1.27)
					(thickness 0.15)
				)
				(justify left bottom)
				(hide yes)
			)
		)
		(property "MPN" "CR0402-FX-1000GLF"
			(at 259.08 15.24 0)
			(effects
				(font
					(size 1.27 1.27)
					(thickness 0.15)
				)
				(justify left bottom)
				(hide yes)
			)
		)
		(property "Val" "100R"
			(at 271.78 34.29 0)
			(effects
				(font
					(size 1.27 1.27)
					(thickness 0.15)
				)
			)
		)
		(property "License" "Apache-2.0"
			(at 259.08 10.16 0)
			(effects
				(font
					(size 1.27 1.27)
					(thickness 0.15)
				)
				(justify left bottom)
				(hide yes)
			)
		)
		(property "Author" "Antmicro"
			(at 259.08 7.62 0)
			(effects
				(font
					(size 1.27 1.27)
					(thickness 0.15)
				)
				(justify left bottom)
				(hide yes)
			)
		)
		(property "Tolerance" "1%"
			(at 259.08 25.4 0)
			(effects
				(font
					(size 1.27 1.27)
				)
				(justify left bottom)
				(hide yes)
			)
		)
		(pin "1"
		)
		(pin "2"
		)
		(instances
			(project "k410t-devboard"
				(path ""
					(reference "R134")
					(unit 1)
				)
			)
		)
	)
	(symbol
		(lib_id "antmicropower:GND")
		(at 129.54 251.46 0)
		(unit 1)
		(exclude_from_sim no)
		(in_bom yes)
		(on_board yes)
		(dnp no)
		(fields_autoplaced yes)
		(property "Reference" "#PWR0162"
			(at 129.54 257.81 0)
			(effects
				(font
					(size 1.27 1.27)
				)
				(hide yes)
			)
		)
		(property "Value" "GND"
			(at 129.54 255.905 0)
			(effects
				(font
					(size 1.27 1.27)
				)
			)
		)
		(property "Footprint" ""
			(at 138.43 259.08 0)
			(effects
				(font
					(size 1.27 1.27)
					(thickness 0.15)
				)
				(justify left bottom)
				(hide yes)
			)
		)
		(property "Datasheet" ""
			(at 138.43 264.16 0)
			(effects
				(font
					(size 1.27 1.27)
					(thickness 0.15)
				)
				(justify left bottom)
				(hide yes)
			)
		)
		(property "Description" ""
			(at 129.54 251.46 0)
			(effects
				(font
					(size 1.27 1.27)
				)
			)
		)
		(property "Author" "Antmicro"
			(at 138.43 259.08 0)
			(effects
				(font
					(size 1.27 1.27)
					(thickness 0.15)
				)
				(justify left bottom)
				(hide yes)
			)
		)
		(property "License" "Apache-2.0"
			(at 138.43 261.62 0)
			(effects
				(font
					(size 1.27 1.27)
					(thickness 0.15)
				)
				(justify left bottom)
				(hide yes)
			)
		)
		(pin "1"
		)
		(instances
			(project "k410t-devboard"
				(path ""
					(reference "#PWR0162")
					(unit 1)
				)
			)
		)
	)
	(symbol
		(lib_id "antmicroTransistorsFETsMOSFETsSingle:BSS138PW")
		(at 179.07 200.66 90)
		(unit 1)
		(exclude_from_sim no)
		(in_bom yes)
		(on_board yes)
		(dnp no)
		(fields_autoplaced yes)
		(property "Reference" "Q15"
			(at 176.53 185.42 90)
			(effects
				(font
					(size 1.27 1.27)
				)
			)
		)
		(property "Value" "BSS138PW"
			(at 176.53 187.96 90)
			(effects
				(font
					(size 1.27 1.27)
					(thickness 0.15)
				)
			)
		)
		(property "Footprint" "antmicro-footprints:SC70-3"
			(at 190.5 177.8 0)
			(effects
				(font
					(size 1.27 1.27)
					(thickness 0.15)
				)
				(justify left bottom)
				(hide yes)
			)
		)
		(property "Datasheet" "https://assets.nexperia.com/documents/data-sheet/BSS138PW.pdf"
			(at 193.04 177.8 0)
			(effects
				(font
					(size 1.27 1.27)
					(thickness 0.15)
				)
				(justify left bottom)
				(hide yes)
			)
		)
		(property "Description" ""
			(at 179.07 200.66 0)
			(effects
				(font
					(size 1.27 1.27)
				)
			)
		)
		(property "MPN" "BSS138PW"
			(at 195.58 177.8 0)
			(effects
				(font
					(size 1.27 1.27)
					(thickness 0.15)
				)
				(justify left bottom)
				(hide yes)
			)
		)
		(property "Manufacturer" "Nexperia"
			(at 198.12 177.8 0)
			(effects
				(font
					(size 1.27 1.27)
					(thickness 0.15)
				)
				(justify left bottom)
				(hide yes)
			)
		)
		(property "Author" "Antmicro"
			(at 200.66 177.8 0)
			(effects
				(font
					(size 1.27 1.27)
					(thickness 0.15)
				)
				(justify left bottom)
				(hide yes)
			)
		)
		(property "License" "Apache-2.0"
			(at 203.2 177.8 0)
			(effects
				(font
					(size 1.27 1.27)
					(thickness 0.15)
				)
				(justify left bottom)
				(hide yes)
			)
		)
		(pin "1"
		)
		(pin "2"
		)
		(pin "3"
		)
		(instances
			(project "k410t-devboard"
				(path ""
					(reference "Q15")
					(unit 1)
				)
			)
		)
	)
	(symbol
		(lib_id "antmicroResistors0402:R_100R_0402")
		(at 140.97 87.63 180)
		(unit 1)
		(exclude_from_sim no)
		(in_bom yes)
		(on_board yes)
		(dnp no)
		(property "Reference" "R124"
			(at 143.51 86.36 0)
			(effects
				(font
					(size 1.27 1.27)
				)
			)
		)
		(property "Value" "R_100R_0402"
			(at 120.65 74.93 0)
			(effects
				(font
					(size 1.27 1.27)
					(thickness 0.15)
				)
				(justify left bottom)
				(hide yes)
			)
		)
		(property "Footprint" "antmicro-footprints:R_0402_1005Metric"
			(at 120.65 72.39 0)
			(effects
				(font
					(size 1.27 1.27)
					(thickness 0.15)
				)
				(justify left bottom)
				(hide yes)
			)
		)
		(property "Datasheet" "https://www.bourns.com/docs/product-datasheets/cr.pdf"
			(at 120.65 69.85 0)
			(effects
				(font
					(size 1.27 1.27)
					(thickness 0.15)
				)
				(justify left bottom)
				(hide yes)
			)
		)
		(property "Description" ""
			(at 140.97 87.63 0)
			(effects
				(font
					(size 1.27 1.27)
				)
			)
		)
		(property "Manufacturer" "Bourns"
			(at 120.65 64.77 0)
			(effects
				(font
					(size 1.27 1.27)
					(thickness 0.15)
				)
				(justify left bottom)
				(hide yes)
			)
		)
		(property "MPN" "CR0402-FX-1000GLF"
			(at 120.65 67.31 0)
			(effects
				(font
					(size 1.27 1.27)
					(thickness 0.15)
				)
				(justify left bottom)
				(hide yes)
			)
		)
		(property "Val" "100R"
			(at 133.35 86.36 0)
			(effects
				(font
					(size 1.27 1.27)
					(thickness 0.15)
				)
			)
		)
		(property "License" "Apache-2.0"
			(at 120.65 62.23 0)
			(effects
				(font
					(size 1.27 1.27)
					(thickness 0.15)
				)
				(justify left bottom)
				(hide yes)
			)
		)
		(property "Author" "Antmicro"
			(at 120.65 59.69 0)
			(effects
				(font
					(size 1.27 1.27)
					(thickness 0.15)
				)
				(justify left bottom)
				(hide yes)
			)
		)
		(property "Tolerance" "1%"
			(at 120.65 77.47 0)
			(effects
				(font
					(size 1.27 1.27)
				)
				(justify left bottom)
				(hide yes)
			)
		)
		(pin "1"
		)
		(pin "2"
		)
		(instances
			(project "k410t-devboard"
				(path ""
					(reference "R124")
					(unit 1)
				)
			)
		)
	)
	(symbol
		(lib_id "antmicropower:+3.3V")
		(at 281.94 185.42 0)
		(unit 1)
		(exclude_from_sim no)
		(in_bom yes)
		(on_board yes)
		(dnp no)
		(fields_autoplaced yes)
		(property "Reference" "#PWR0167"
			(at 281.94 189.23 0)
			(effects
				(font
					(size 1.27 1.27)
				)
				(hide yes)
			)
		)
		(property "Value" "+3V3"
			(at 281.94 181.864 0)
			(effects
				(font
					(size 1.27 1.27)
				)
			)
		)
		(property "Footprint" ""
			(at 281.94 185.42 0)
			(effects
				(font
					(size 1.27 1.27)
				)
				(hide yes)
			)
		)
		(property "Datasheet" ""
			(at 281.94 185.42 0)
			(effects
				(font
					(size 1.27 1.27)
				)
				(hide yes)
			)
		)
		(property "Description" ""
			(at 281.94 185.42 0)
			(effects
				(font
					(size 1.27 1.27)
				)
			)
		)
		(pin "1"
		)
		(instances
			(project "k410t-devboard"
				(path ""
					(reference "#PWR0167")
					(unit 1)
				)
			)
		)
	)
	(symbol
		(lib_id "antmicroResistors0402:R_100R_0402")
		(at 356.87 35.56 180)
		(unit 1)
		(exclude_from_sim no)
		(in_bom yes)
		(on_board yes)
		(dnp no)
		(property "Reference" "R143"
			(at 359.41 34.29 0)
			(effects
				(font
					(size 1.27 1.27)
				)
			)
		)
		(property "Value" "R_100R_0402"
			(at 336.55 22.86 0)
			(effects
				(font
					(size 1.27 1.27)
					(thickness 0.15)
				)
				(justify left bottom)
				(hide yes)
			)
		)
		(property "Footprint" "antmicro-footprints:R_0402_1005Metric"
			(at 336.55 20.32 0)
			(effects
				(font
					(size 1.27 1.27)
					(thickness 0.15)
				)
				(justify left bottom)
				(hide yes)
			)
		)
		(property "Datasheet" "https://www.bourns.com/docs/product-datasheets/cr.pdf"
			(at 336.55 17.78 0)
			(effects
				(font
					(size 1.27 1.27)
					(thickness 0.15)
				)
				(justify left bottom)
				(hide yes)
			)
		)
		(property "Description" ""
			(at 356.87 35.56 0)
			(effects
				(font
					(size 1.27 1.27)
				)
			)
		)
		(property "Manufacturer" "Bourns"
			(at 336.55 12.7 0)
			(effects
				(font
					(size 1.27 1.27)
					(thickness 0.15)
				)
				(justify left bottom)
				(hide yes)
			)
		)
		(property "MPN" "CR0402-FX-1000GLF"
			(at 336.55 15.24 0)
			(effects
				(font
					(size 1.27 1.27)
					(thickness 0.15)
				)
				(justify left bottom)
				(hide yes)
			)
		)
		(property "Val" "100R"
			(at 349.25 34.29 0)
			(effects
				(font
					(size 1.27 1.27)
					(thickness 0.15)
				)
			)
		)
		(property "License" "Apache-2.0"
			(at 336.55 10.16 0)
			(effects
				(font
					(size 1.27 1.27)
					(thickness 0.15)
				)
				(justify left bottom)
				(hide yes)
			)
		)
		(property "Author" "Antmicro"
			(at 336.55 7.62 0)
			(effects
				(font
					(size 1.27 1.27)
					(thickness 0.15)
				)
				(justify left bottom)
				(hide yes)
			)
		)
		(property "Tolerance" "1%"
			(at 336.55 25.4 0)
			(effects
				(font
					(size 1.27 1.27)
				)
				(justify left bottom)
				(hide yes)
			)
		)
		(pin "1"
		)
		(pin "2"
		)
		(instances
			(project "k410t-devboard"
				(path ""
					(reference "R143")
					(unit 1)
				)
			)
		)
	)
	(symbol
		(lib_id "antmicroResistorNetworksArrays:4x10k_0201_array")
		(at 234.95 265.43 180)
		(unit 1)
		(exclude_from_sim no)
		(in_bom yes)
		(on_board yes)
		(dnp no)
		(property "Reference" "R132"
			(at 217.17 259.715 0)
			(effects
				(font
					(size 1.27 1.27)
				)
			)
		)
		(property "Value" "4x10k_0201_array"
			(at 208.28 257.81 0)
			(effects
				(font
					(size 1.27 1.27)
					(thickness 0.15)
				)
				(justify left bottom)
				(hide yes)
			)
		)
		(property "Footprint" "antmicro-footprints:R_Array_4x0201_Panasonic_EXB18V"
			(at 208.28 252.73 0)
			(effects
				(font
					(size 1.27 1.27)
					(thickness 0.15)
				)
				(justify left bottom)
				(hide yes)
			)
		)
		(property "Datasheet" "http://industrial.panasonic.com/cdbs/www-data/pdf/AOC0000/AOC0000C14.pdf"
			(at 208.28 250.19 0)
			(effects
				(font
					(size 1.27 1.27)
					(thickness 0.15)
				)
				(justify left bottom)
				(hide yes)
			)
		)
		(property "Description" ""
			(at 234.95 265.43 0)
			(effects
				(font
					(size 1.27 1.27)
				)
			)
		)
		(property "MPN" "EXB-18V103JX"
			(at 208.28 247.65 0)
			(effects
				(font
					(size 1.27 1.27)
					(thickness 0.15)
				)
				(justify left bottom)
				(hide yes)
			)
		)
		(property "Manufacturer" "Panasonic"
			(at 208.28 245.11 0)
			(effects
				(font
					(size 1.27 1.27)
					(thickness 0.15)
				)
				(justify left bottom)
				(hide yes)
			)
		)
		(property "Val" "4x10k_0201"
			(at 217.17 262.255 0)
			(effects
				(font
					(size 1.27 1.27)
					(thickness 0.15)
				)
			)
		)
		(property "Author" "Antmicro"
			(at 208.28 242.57 0)
			(effects
				(font
					(size 1.27 1.27)
					(thickness 0.15)
				)
				(justify left bottom)
				(hide yes)
			)
		)
		(property "License" "Apache-2.0"
			(at 208.28 240.03 0)
			(effects
				(font
					(size 1.27 1.27)
					(thickness 0.15)
				)
				(justify left bottom)
				(hide yes)
			)
		)
		(pin "1"
		)
		(pin "2"
		)
		(pin "3"
		)
		(pin "4"
		)
		(pin "5"
		)
		(pin "6"
		)
		(pin "7"
		)
		(pin "8"
		)
		(instances
			(project "k410t-devboard"
				(path ""
					(reference "R132")
					(unit 1)
				)
			)
		)
	)
	(symbol
		(lib_id "antmicroResistors0402:R_100k_0402")
		(at 107.95 201.93 0)
		(unit 1)
		(exclude_from_sim no)
		(in_bom yes)
		(on_board yes)
		(dnp no)
		(property "Reference" "R355"
			(at 110.49 196.85 0)
			(effects
				(font
					(size 1.27 1.27)
				)
			)
		)
		(property "Value" "R_100k_0402"
			(at 128.27 214.63 0)
			(effects
				(font
					(size 1.27 1.27)
					(thickness 0.15)
				)
				(justify left bottom)
				(hide yes)
			)
		)
		(property "Footprint" "antmicro-footprints:R_0402_1005Metric"
			(at 128.27 217.17 0)
			(effects
				(font
					(size 1.27 1.27)
					(thickness 0.15)
				)
				(justify left bottom)
				(hide yes)
			)
		)
		(property "Datasheet" "https://www.bourns.com/docs/product-datasheets/cr.pdf"
			(at 128.27 219.71 0)
			(effects
				(font
					(size 1.27 1.27)
					(thickness 0.15)
				)
				(justify left bottom)
				(hide yes)
			)
		)
		(property "Description" ""
			(at 107.95 201.93 0)
			(effects
				(font
					(size 1.27 1.27)
				)
			)
		)
		(property "Manufacturer" "Bourns"
			(at 128.27 224.79 0)
			(effects
				(font
					(size 1.27 1.27)
					(thickness 0.15)
				)
				(justify left bottom)
				(hide yes)
			)
		)
		(property "MPN" "CR0402-FX-1003GLF"
			(at 128.27 222.25 0)
			(effects
				(font
					(size 1.27 1.27)
					(thickness 0.15)
				)
				(justify left bottom)
				(hide yes)
			)
		)
		(property "Val" "100k"
			(at 110.49 199.39 0)
			(effects
				(font
					(size 1.27 1.27)
					(thickness 0.15)
				)
			)
		)
		(property "License" "Apache-2.0"
			(at 128.27 227.33 0)
			(effects
				(font
					(size 1.27 1.27)
					(thickness 0.15)
				)
				(justify left bottom)
				(hide yes)
			)
		)
		(property "Author" "Antmicro"
			(at 128.27 229.87 0)
			(effects
				(font
					(size 1.27 1.27)
					(thickness 0.15)
				)
				(justify left bottom)
				(hide yes)
			)
		)
		(property "Tolerance" "1%"
			(at 128.27 212.09 0)
			(effects
				(font
					(size 1.27 1.27)
				)
				(justify left bottom)
				(hide yes)
			)
		)
		(pin "1"
		)
		(pin "2"
		)
		(instances
			(project "k410t-devboard"
				(path ""
					(reference "R355")
					(unit 1)
				)
			)
		)
	)
	(symbol
		(lib_id "antmicroTransistorsFETsMOSFETsSingle:BSS138PW")
		(at 96.52 200.66 90)
		(unit 1)
		(exclude_from_sim no)
		(in_bom yes)
		(on_board yes)
		(dnp no)
		(fields_autoplaced yes)
		(property "Reference" "Q10"
			(at 93.98 185.42 90)
			(effects
				(font
					(size 1.27 1.27)
				)
			)
		)
		(property "Value" "BSS138PW"
			(at 93.98 187.96 90)
			(effects
				(font
					(size 1.27 1.27)
					(thickness 0.15)
				)
			)
		)
		(property "Footprint" "antmicro-footprints:SC70-3"
			(at 107.95 177.8 0)
			(effects
				(font
					(size 1.27 1.27)
					(thickness 0.15)
				)
				(justify left bottom)
				(hide yes)
			)
		)
		(property "Datasheet" "https://assets.nexperia.com/documents/data-sheet/BSS138PW.pdf"
			(at 110.49 177.8 0)
			(effects
				(font
					(size 1.27 1.27)
					(thickness 0.15)
				)
				(justify left bottom)
				(hide yes)
			)
		)
		(property "Description" ""
			(at 96.52 200.66 0)
			(effects
				(font
					(size 1.27 1.27)
				)
			)
		)
		(property "MPN" "BSS138PW"
			(at 113.03 177.8 0)
			(effects
				(font
					(size 1.27 1.27)
					(thickness 0.15)
				)
				(justify left bottom)
				(hide yes)
			)
		)
		(property "Manufacturer" "Nexperia"
			(at 115.57 177.8 0)
			(effects
				(font
					(size 1.27 1.27)
					(thickness 0.15)
				)
				(justify left bottom)
				(hide yes)
			)
		)
		(property "Author" "Antmicro"
			(at 118.11 177.8 0)
			(effects
				(font
					(size 1.27 1.27)
					(thickness 0.15)
				)
				(justify left bottom)
				(hide yes)
			)
		)
		(property "License" "Apache-2.0"
			(at 120.65 177.8 0)
			(effects
				(font
					(size 1.27 1.27)
					(thickness 0.15)
				)
				(justify left bottom)
				(hide yes)
			)
		)
		(pin "1"
		)
		(pin "2"
		)
		(pin "3"
		)
		(instances
			(project "k410t-devboard"
				(path ""
					(reference "Q10")
					(unit 1)
				)
			)
		)
	)
	(symbol
		(lib_id "antmicropower:GND")
		(at 104.14 194.31 0)
		(unit 1)
		(exclude_from_sim no)
		(in_bom yes)
		(on_board yes)
		(dnp no)
		(property "Reference" "#PWR0145"
			(at 104.14 200.66 0)
			(effects
				(font
					(size 1.27 1.27)
				)
				(hide yes)
			)
		)
		(property "Value" "GND"
			(at 104.14 198.12 0)
			(effects
				(font
					(size 1.27 1.27)
				)
			)
		)
		(property "Footprint" ""
			(at 113.03 201.93 0)
			(effects
				(font
					(size 1.27 1.27)
					(thickness 0.15)
				)
				(justify left bottom)
				(hide yes)
			)
		)
		(property "Datasheet" ""
			(at 113.03 207.01 0)
			(effects
				(font
					(size 1.27 1.27)
					(thickness 0.15)
				)
				(justify left bottom)
				(hide yes)
			)
		)
		(property "Description" ""
			(at 104.14 194.31 0)
			(effects
				(font
					(size 1.27 1.27)
				)
			)
		)
		(property "Author" "Antmicro"
			(at 113.03 201.93 0)
			(effects
				(font
					(size 1.27 1.27)
					(thickness 0.15)
				)
				(justify left bottom)
				(hide yes)
			)
		)
		(property "License" "Apache-2.0"
			(at 113.03 204.47 0)
			(effects
				(font
					(size 1.27 1.27)
					(thickness 0.15)
				)
				(justify left bottom)
				(hide yes)
			)
		)
		(pin "1"
		)
		(instances
			(project "k410t-devboard"
				(path ""
					(reference "#PWR0145")
					(unit 1)
				)
			)
		)
	)
	(symbol
		(lib_id "antmicropower:GND")
		(at 96.52 261.62 0)
		(unit 1)
		(exclude_from_sim no)
		(in_bom yes)
		(on_board yes)
		(dnp no)
		(fields_autoplaced yes)
		(property "Reference" "#PWR0138"
			(at 96.52 267.97 0)
			(effects
				(font
					(size 1.27 1.27)
				)
				(hide yes)
			)
		)
		(property "Value" "GND"
			(at 96.52 266.065 0)
			(effects
				(font
					(size 1.27 1.27)
				)
			)
		)
		(property "Footprint" ""
			(at 105.41 269.24 0)
			(effects
				(font
					(size 1.27 1.27)
					(thickness 0.15)
				)
				(justify left bottom)
				(hide yes)
			)
		)
		(property "Datasheet" ""
			(at 105.41 274.32 0)
			(effects
				(font
					(size 1.27 1.27)
					(thickness 0.15)
				)
				(justify left bottom)
				(hide yes)
			)
		)
		(property "Description" ""
			(at 96.52 261.62 0)
			(effects
				(font
					(size 1.27 1.27)
				)
			)
		)
		(property "Author" "Antmicro"
			(at 105.41 269.24 0)
			(effects
				(font
					(size 1.27 1.27)
					(thickness 0.15)
				)
				(justify left bottom)
				(hide yes)
			)
		)
		(property "License" "Apache-2.0"
			(at 105.41 271.78 0)
			(effects
				(font
					(size 1.27 1.27)
					(thickness 0.15)
				)
				(justify left bottom)
				(hide yes)
			)
		)
		(pin "1"
		)
		(instances
			(project "k410t-devboard"
				(path ""
					(reference "#PWR0138")
					(unit 1)
				)
			)
		)
	)
	(symbol
		(lib_id "antmicroTransistorsFETsMOSFETsSingle:BSS138PW")
		(at 179.07 162.56 90)
		(unit 1)
		(exclude_from_sim no)
		(in_bom yes)
		(on_board yes)
		(dnp no)
		(fields_autoplaced yes)
		(property "Reference" "Q13"
			(at 176.53 147.32 90)
			(effects
				(font
					(size 1.27 1.27)
				)
			)
		)
		(property "Value" "BSS138PW"
			(at 176.53 149.86 90)
			(effects
				(font
					(size 1.27 1.27)
					(thickness 0.15)
				)
			)
		)
		(property "Footprint" "antmicro-footprints:SC70-3"
			(at 190.5 139.7 0)
			(effects
				(font
					(size 1.27 1.27)
					(thickness 0.15)
				)
				(justify left bottom)
				(hide yes)
			)
		)
		(property "Datasheet" "https://assets.nexperia.com/documents/data-sheet/BSS138PW.pdf"
			(at 193.04 139.7 0)
			(effects
				(font
					(size 1.27 1.27)
					(thickness 0.15)
				)
				(justify left bottom)
				(hide yes)
			)
		)
		(property "Description" ""
			(at 179.07 162.56 0)
			(effects
				(font
					(size 1.27 1.27)
				)
			)
		)
		(property "MPN" "BSS138PW"
			(at 195.58 139.7 0)
			(effects
				(font
					(size 1.27 1.27)
					(thickness 0.15)
				)
				(justify left bottom)
				(hide yes)
			)
		)
		(property "Manufacturer" "Nexperia"
			(at 198.12 139.7 0)
			(effects
				(font
					(size 1.27 1.27)
					(thickness 0.15)
				)
				(justify left bottom)
				(hide yes)
			)
		)
		(property "Author" "Antmicro"
			(at 200.66 139.7 0)
			(effects
				(font
					(size 1.27 1.27)
					(thickness 0.15)
				)
				(justify left bottom)
				(hide yes)
			)
		)
		(property "License" "Apache-2.0"
			(at 203.2 139.7 0)
			(effects
				(font
					(size 1.27 1.27)
					(thickness 0.15)
				)
				(justify left bottom)
				(hide yes)
			)
		)
		(pin "1"
		)
		(pin "2"
		)
		(pin "3"
		)
		(instances
			(project "k410t-devboard"
				(path ""
					(reference "Q13")
					(unit 1)
				)
			)
		)
	)
	(symbol
		(lib_id "antmicroTVSDiodes:ESDA25P35-1U1M")
		(at 377.19 92.71 270)
		(unit 1)
		(exclude_from_sim no)
		(in_bom yes)
		(on_board yes)
		(dnp no)
		(property "Reference" "D37"
			(at 374.65 96.8375 90)
			(effects
				(font
					(size 1.27 1.27)
				)
				(justify right)
			)
		)
		(property "Value" "ESDA25P35-1U1M"
			(at 374.65 94.2976 90)
			(effects
				(font
					(size 1.27 1.27)
					(thickness 0.15)
				)
				(justify right)
				(hide yes)
			)
		)
		(property "Footprint" "antmicro-footprints:QFN-2L_1.6x1x0.55mm"
			(at 367.03 116.84 0)
			(effects
				(font
					(size 1.27 1.27)
					(thickness 0.15)
				)
				(justify left bottom)
				(hide yes)
			)
		)
		(property "Datasheet" "https://www.st.com/resource/en/datasheet/esda25p35-1u1m.pdf"
			(at 364.49 116.84 0)
			(effects
				(font
					(size 1.27 1.27)
					(thickness 0.15)
				)
				(justify left bottom)
				(hide yes)
			)
		)
		(property "Description" ""
			(at 377.19 92.71 0)
			(effects
				(font
					(size 1.27 1.27)
				)
			)
		)
		(property "MPN" "ESDA25P35-1U1M"
			(at 374.65 94.2975 90)
			(effects
				(font
					(size 1.27 1.27)
					(thickness 0.15)
				)
				(justify right)
			)
		)
		(property "Manufacturer" "STMicroelectronics"
			(at 359.41 116.84 0)
			(effects
				(font
					(size 1.27 1.27)
					(thickness 0.15)
				)
				(justify left bottom)
				(hide yes)
			)
		)
		(property "Author" "Antmicro"
			(at 356.87 116.84 0)
			(effects
				(font
					(size 1.27 1.27)
					(thickness 0.15)
				)
				(justify left bottom)
				(hide yes)
			)
		)
		(property "License" "Apache-2.0"
			(at 354.33 116.84 0)
			(effects
				(font
					(size 1.27 1.27)
					(thickness 0.15)
				)
				(justify left bottom)
				(hide yes)
			)
		)
		(property "Public" "False"
			(at 359.41 113.03 0)
			(effects
				(font
					(size 1.27 1.27)
				)
				(justify left bottom)
				(hide yes)
			)
		)
		(pin "1"
		)
		(pin "2"
		)
		(instances
			(project "k410t-devboard"
				(path ""
					(reference "D37")
					(unit 1)
				)
			)
		)
	)
	(symbol
		(lib_id "antmicroResistors0402:R_100R_0402")
		(at 356.87 45.72 180)
		(unit 1)
		(exclude_from_sim no)
		(in_bom yes)
		(on_board yes)
		(dnp no)
		(property "Reference" "R146"
			(at 359.41 44.45 0)
			(effects
				(font
					(size 1.27 1.27)
				)
			)
		)
		(property "Value" "R_100R_0402"
			(at 336.55 33.02 0)
			(effects
				(font
					(size 1.27 1.27)
					(thickness 0.15)
				)
				(justify left bottom)
				(hide yes)
			)
		)
		(property "Footprint" "antmicro-footprints:R_0402_1005Metric"
			(at 336.55 30.48 0)
			(effects
				(font
					(size 1.27 1.27)
					(thickness 0.15)
				)
				(justify left bottom)
				(hide yes)
			)
		)
		(property "Datasheet" "https://www.bourns.com/docs/product-datasheets/cr.pdf"
			(at 336.55 27.94 0)
			(effects
				(font
					(size 1.27 1.27)
					(thickness 0.15)
				)
				(justify left bottom)
				(hide yes)
			)
		)
		(property "Description" ""
			(at 356.87 45.72 0)
			(effects
				(font
					(size 1.27 1.27)
				)
			)
		)
		(property "Manufacturer" "Bourns"
			(at 336.55 22.86 0)
			(effects
				(font
					(size 1.27 1.27)
					(thickness 0.15)
				)
				(justify left bottom)
				(hide yes)
			)
		)
		(property "MPN" "CR0402-FX-1000GLF"
			(at 336.55 25.4 0)
			(effects
				(font
					(size 1.27 1.27)
					(thickness 0.15)
				)
				(justify left bottom)
				(hide yes)
			)
		)
		(property "Val" "100R"
			(at 349.25 44.45 0)
			(effects
				(font
					(size 1.27 1.27)
					(thickness 0.15)
				)
			)
		)
		(property "License" "Apache-2.0"
			(at 336.55 20.32 0)
			(effects
				(font
					(size 1.27 1.27)
					(thickness 0.15)
				)
				(justify left bottom)
				(hide yes)
			)
		)
		(property "Author" "Antmicro"
			(at 336.55 17.78 0)
			(effects
				(font
					(size 1.27 1.27)
					(thickness 0.15)
				)
				(justify left bottom)
				(hide yes)
			)
		)
		(property "Tolerance" "1%"
			(at 336.55 35.56 0)
			(effects
				(font
					(size 1.27 1.27)
				)
				(justify left bottom)
				(hide yes)
			)
		)
		(pin "1"
		)
		(pin "2"
		)
		(instances
			(project "k410t-devboard"
				(path ""
					(reference "R146")
					(unit 1)
				)
			)
		)
	)
	(symbol
		(lib_id "antmicroTVSDiodes:ESDA25P35-1U1M")
		(at 354.33 114.3 90)
		(mirror x)
		(unit 1)
		(exclude_from_sim no)
		(in_bom yes)
		(on_board yes)
		(dnp no)
		(property "Reference" "D36"
			(at 351.79 118.4275 90)
			(effects
				(font
					(size 1.27 1.27)
				)
				(justify left)
			)
		)
		(property "Value" "ESDA25P35-1U1M"
			(at 356.87 115.8875 90)
			(effects
				(font
					(size 1.27 1.27)
					(thickness 0.15)
				)
				(justify right)
				(hide yes)
			)
		)
		(property "Footprint" "antmicro-footprints:QFN-2L_1.6x1x0.55mm"
			(at 364.49 138.43 0)
			(effects
				(font
					(size 1.27 1.27)
					(thickness 0.15)
				)
				(justify left bottom)
				(hide yes)
			)
		)
		(property "Datasheet" "https://www.st.com/resource/en/datasheet/esda25p35-1u1m.pdf"
			(at 367.03 138.43 0)
			(effects
				(font
					(size 1.27 1.27)
					(thickness 0.15)
				)
				(justify left bottom)
				(hide yes)
			)
		)
		(property "Description" ""
			(at 354.33 114.3 0)
			(effects
				(font
					(size 1.27 1.27)
				)
			)
		)
		(property "MPN" "ESDA25P35-1U1M"
			(at 351.79 115.8875 90)
			(effects
				(font
					(size 1.27 1.27)
					(thickness 0.15)
				)
				(justify left)
			)
		)
		(property "Manufacturer" "STMicroelectronics"
			(at 372.11 138.43 0)
			(effects
				(font
					(size 1.27 1.27)
					(thickness 0.15)
				)
				(justify left bottom)
				(hide yes)
			)
		)
		(property "Author" "Antmicro"
			(at 374.65 138.43 0)
			(effects
				(font
					(size 1.27 1.27)
					(thickness 0.15)
				)
				(justify left bottom)
				(hide yes)
			)
		)
		(property "License" "Apache-2.0"
			(at 377.19 138.43 0)
			(effects
				(font
					(size 1.27 1.27)
					(thickness 0.15)
				)
				(justify left bottom)
				(hide yes)
			)
		)
		(property "Public" "False"
			(at 372.11 134.62 0)
			(effects
				(font
					(size 1.27 1.27)
				)
				(justify left bottom)
				(hide yes)
			)
		)
		(pin "1"
		)
		(pin "2"
		)
		(instances
			(project "k410t-devboard"
				(path ""
					(reference "D36")
					(unit 1)
				)
			)
		)
	)
	(symbol
		(lib_id "antmicropower:GND")
		(at 198.12 220.98 0)
		(unit 1)
		(exclude_from_sim no)
		(in_bom yes)
		(on_board yes)
		(dnp no)
		(property "Reference" "#PWR0181"
			(at 198.12 227.33 0)
			(effects
				(font
					(size 1.27 1.27)
				)
				(hide yes)
			)
		)
		(property "Value" "GND"
			(at 198.12 224.79 0)
			(effects
				(font
					(size 1.27 1.27)
				)
			)
		)
		(property "Footprint" ""
			(at 207.01 228.6 0)
			(effects
				(font
					(size 1.27 1.27)
					(thickness 0.15)
				)
				(justify left bottom)
				(hide yes)
			)
		)
		(property "Datasheet" ""
			(at 207.01 233.68 0)
			(effects
				(font
					(size 1.27 1.27)
					(thickness 0.15)
				)
				(justify left bottom)
				(hide yes)
			)
		)
		(property "Description" ""
			(at 198.12 220.98 0)
			(effects
				(font
					(size 1.27 1.27)
				)
			)
		)
		(property "Author" "Antmicro"
			(at 207.01 228.6 0)
			(effects
				(font
					(size 1.27 1.27)
					(thickness 0.15)
				)
				(justify left bottom)
				(hide yes)
			)
		)
		(property "License" "Apache-2.0"
			(at 207.01 231.14 0)
			(effects
				(font
					(size 1.27 1.27)
					(thickness 0.15)
				)
				(justify left bottom)
				(hide yes)
			)
		)
		(pin "1"
		)
		(instances
			(project "k410t-devboard"
				(path ""
					(reference "#PWR0181")
					(unit 1)
				)
			)
		)
	)
	(symbol
		(lib_id "antmicropower:+5V")
		(at 72.39 242.57 0)
		(unit 1)
		(exclude_from_sim no)
		(in_bom yes)
		(on_board yes)
		(dnp no)
		(property "Reference" "#PWR0133"
			(at 72.39 246.38 0)
			(effects
				(font
					(size 1.27 1.27)
				)
				(hide yes)
			)
		)
		(property "Value" "+5V"
			(at 71.755 238.76 0)
			(effects
				(font
					(size 1.27 1.27)
				)
			)
		)
		(property "Footprint" ""
			(at 72.39 242.57 0)
			(effects
				(font
					(size 1.27 1.27)
				)
				(hide yes)
			)
		)
		(property "Datasheet" ""
			(at 72.39 242.57 0)
			(effects
				(font
					(size 1.27 1.27)
				)
				(hide yes)
			)
		)
		(property "Description" ""
			(at 72.39 242.57 0)
			(effects
				(font
					(size 1.27 1.27)
				)
			)
		)
		(property "Author" "Antmicro"
			(at 87.63 250.19 0)
			(effects
				(font
					(size 1.27 1.27)
					(thickness 0.15)
				)
				(justify left bottom)
				(hide yes)
			)
		)
		(property "License" "Apache-2.0"
			(at 87.63 252.73 0)
			(effects
				(font
					(size 1.27 1.27)
					(thickness 0.15)
				)
				(justify left bottom)
				(hide yes)
			)
		)
		(pin "1"
		)
		(instances
			(project "k410t-devboard"
				(path ""
					(reference "#PWR0133")
					(unit 1)
				)
			)
		)
	)
	(symbol
		(lib_id "antmicroCapacitors0402:C_1u_0402")
		(at 170.18 250.19 90)
		(unit 1)
		(exclude_from_sim no)
		(in_bom yes)
		(on_board yes)
		(dnp no)
		(property "Reference" "C217"
			(at 170.815 245.745 90)
			(effects
				(font
					(size 1.27 1.27)
				)
				(justify right)
			)
		)
		(property "Value" "C_1u_0402"
			(at 180.34 229.87 0)
			(effects
				(font
					(size 1.27 1.27)
					(thickness 0.15)
				)
				(justify left bottom)
				(hide yes)
			)
		)
		(property "Footprint" "antmicro-footprints:C_0402_1005Metric"
			(at 182.88 229.87 0)
			(effects
				(font
					(size 1.27 1.27)
					(thickness 0.15)
				)
				(justify left bottom)
				(hide yes)
			)
		)
		(property "Datasheet" "https://product.tdk.com/en/search/capacitor/ceramic/mlcc/info?part_no=C1005X6S1A105K050BC"
			(at 185.42 229.87 0)
			(effects
				(font
					(size 1.27 1.27)
					(thickness 0.15)
				)
				(justify left bottom)
				(hide yes)
			)
		)
		(property "Description" ""
			(at 170.18 250.19 0)
			(effects
				(font
					(size 1.27 1.27)
				)
			)
		)
		(property "Manufacturer" "TDK"
			(at 190.5 229.87 0)
			(effects
				(font
					(size 1.27 1.27)
					(thickness 0.15)
				)
				(justify left bottom)
				(hide yes)
			)
		)
		(property "MPN" "C1005X6S1A105K050BC"
			(at 187.96 229.87 0)
			(effects
				(font
					(size 1.27 1.27)
					(thickness 0.15)
				)
				(justify left bottom)
				(hide yes)
			)
		)
		(property "Val" "1u"
			(at 170.815 249.555 90)
			(effects
				(font
					(size 1.27 1.27)
					(thickness 0.15)
				)
				(justify right)
			)
		)
		(property "License" "Apache-2.0"
			(at 193.04 229.87 0)
			(effects
				(font
					(size 1.27 1.27)
					(thickness 0.15)
				)
				(justify left bottom)
				(hide yes)
			)
		)
		(property "Author" "Antmicro"
			(at 195.58 229.87 0)
			(effects
				(font
					(size 1.27 1.27)
					(thickness 0.15)
				)
				(justify left bottom)
				(hide yes)
			)
		)
		(property "Voltage" ""
			(at 198.12 229.87 0)
			(effects
				(font
					(size 1.27 1.27)
				)
				(justify left bottom)
				(hide yes)
			)
		)
		(property "Dielectric" ""
			(at 200.66 229.87 0)
			(effects
				(font
					(size 1.27 1.27)
				)
				(justify left bottom)
				(hide yes)
			)
		)
		(pin "1"
		)
		(pin "2"
		)
		(instances
			(project "k410t-devboard"
				(path ""
					(reference "C217")
					(unit 1)
				)
			)
		)
	)
	(symbol
		(lib_id "antmicroResistors0402:R_10k_0402")
		(at 377.19 83.82 270)
		(unit 1)
		(exclude_from_sim no)
		(in_bom yes)
		(on_board yes)
		(dnp no)
		(fields_autoplaced yes)
		(property "Reference" "R148"
			(at 379.095 85.0899 90)
			(effects
				(font
					(size 1.27 1.27)
				)
				(justify left)
			)
		)
		(property "Value" "R_10k_0402"
			(at 364.49 104.14 0)
			(effects
				(font
					(size 1.27 1.27)
					(thickness 0.15)
				)
				(justify left bottom)
				(hide yes)
			)
		)
		(property "Footprint" "antmicro-footprints:R_0402_1005Metric"
			(at 361.95 104.14 0)
			(effects
				(font
					(size 1.27 1.27)
					(thickness 0.15)
				)
				(justify left bottom)
				(hide yes)
			)
		)
		(property "Datasheet" "https://www.bourns.com/docs/product-datasheets/cr.pdf"
			(at 359.41 104.14 0)
			(effects
				(font
					(size 1.27 1.27)
					(thickness 0.15)
				)
				(justify left bottom)
				(hide yes)
			)
		)
		(property "Description" ""
			(at 377.19 83.82 0)
			(effects
				(font
					(size 1.27 1.27)
				)
			)
		)
		(property "Manufacturer" "Bourns"
			(at 354.33 104.14 0)
			(effects
				(font
					(size 1.27 1.27)
					(thickness 0.15)
				)
				(justify left bottom)
				(hide yes)
			)
		)
		(property "MPN" "CR0402-FX-1002GLF"
			(at 356.87 104.14 0)
			(effects
				(font
					(size 1.27 1.27)
					(thickness 0.15)
				)
				(justify left bottom)
				(hide yes)
			)
		)
		(property "Val" "10k"
			(at 379.095 87.6299 90)
			(effects
				(font
					(size 1.27 1.27)
					(thickness 0.15)
				)
				(justify left)
			)
		)
		(property "License" "Apache-2.0"
			(at 351.79 104.14 0)
			(effects
				(font
					(size 1.27 1.27)
					(thickness 0.15)
				)
				(justify left bottom)
				(hide yes)
			)
		)
		(property "Author" "Antmicro"
			(at 349.25 104.14 0)
			(effects
				(font
					(size 1.27 1.27)
					(thickness 0.15)
				)
				(justify left bottom)
				(hide yes)
			)
		)
		(property "Tolerance" "1%"
			(at 367.03 104.14 0)
			(effects
				(font
					(size 1.27 1.27)
				)
				(justify left bottom)
				(hide yes)
			)
		)
		(pin "1"
		)
		(pin "2"
		)
		(instances
			(project "k410t-devboard"
				(path ""
					(reference "R148")
					(unit 1)
				)
			)
		)
	)
	(symbol
		(lib_id "antmicroTransistorsFETsMOSFETsSingle:BSS138PW")
		(at 179.07 181.61 90)
		(unit 1)
		(exclude_from_sim no)
		(in_bom yes)
		(on_board yes)
		(dnp no)
		(fields_autoplaced yes)
		(property "Reference" "Q14"
			(at 176.53 166.37 90)
			(effects
				(font
					(size 1.27 1.27)
				)
			)
		)
		(property "Value" "BSS138PW"
			(at 176.53 168.91 90)
			(effects
				(font
					(size 1.27 1.27)
					(thickness 0.15)
				)
			)
		)
		(property "Footprint" "antmicro-footprints:SC70-3"
			(at 190.5 158.75 0)
			(effects
				(font
					(size 1.27 1.27)
					(thickness 0.15)
				)
				(justify left bottom)
				(hide yes)
			)
		)
		(property "Datasheet" "https://assets.nexperia.com/documents/data-sheet/BSS138PW.pdf"
			(at 193.04 158.75 0)
			(effects
				(font
					(size 1.27 1.27)
					(thickness 0.15)
				)
				(justify left bottom)
				(hide yes)
			)
		)
		(property "Description" ""
			(at 179.07 181.61 0)
			(effects
				(font
					(size 1.27 1.27)
				)
			)
		)
		(property "MPN" "BSS138PW"
			(at 195.58 158.75 0)
			(effects
				(font
					(size 1.27 1.27)
					(thickness 0.15)
				)
				(justify left bottom)
				(hide yes)
			)
		)
		(property "Manufacturer" "Nexperia"
			(at 198.12 158.75 0)
			(effects
				(font
					(size 1.27 1.27)
					(thickness 0.15)
				)
				(justify left bottom)
				(hide yes)
			)
		)
		(property "Author" "Antmicro"
			(at 200.66 158.75 0)
			(effects
				(font
					(size 1.27 1.27)
					(thickness 0.15)
				)
				(justify left bottom)
				(hide yes)
			)
		)
		(property "License" "Apache-2.0"
			(at 203.2 158.75 0)
			(effects
				(font
					(size 1.27 1.27)
					(thickness 0.15)
				)
				(justify left bottom)
				(hide yes)
			)
		)
		(pin "1"
		)
		(pin "2"
		)
		(pin "3"
		)
		(instances
			(project "k410t-devboard"
				(path ""
					(reference "Q14")
					(unit 1)
				)
			)
		)
	)
	(symbol
		(lib_id "antmicropower:+3.3V")
		(at 132.08 189.23 0)
		(unit 1)
		(exclude_from_sim no)
		(in_bom yes)
		(on_board yes)
		(dnp no)
		(fields_autoplaced yes)
		(property "Reference" "#PWR0153"
			(at 132.08 193.04 0)
			(effects
				(font
					(size 1.27 1.27)
				)
				(hide yes)
			)
		)
		(property "Value" "+3V3"
			(at 132.08 185.674 0)
			(effects
				(font
					(size 1.27 1.27)
				)
			)
		)
		(property "Footprint" ""
			(at 132.08 189.23 0)
			(effects
				(font
					(size 1.27 1.27)
				)
				(hide yes)
			)
		)
		(property "Datasheet" ""
			(at 132.08 189.23 0)
			(effects
				(font
					(size 1.27 1.27)
				)
				(hide yes)
			)
		)
		(property "Description" ""
			(at 132.08 189.23 0)
			(effects
				(font
					(size 1.27 1.27)
				)
			)
		)
		(pin "1"
		)
		(instances
			(project "k410t-devboard"
				(path ""
					(reference "#PWR0153")
					(unit 1)
				)
			)
		)
	)
	(symbol
		(lib_id "antmicropower:+1V8")
		(at 279.4 100.965 0)
		(unit 1)
		(exclude_from_sim no)
		(in_bom yes)
		(on_board yes)
		(dnp no)
		(fields_autoplaced yes)
		(property "Reference" "#PWR0165"
			(at 279.4 104.775 0)
			(effects
				(font
					(size 1.27 1.27)
				)
				(hide yes)
			)
		)
		(property "Value" "+1V8"
			(at 279.4 97.409 0)
			(effects
				(font
					(size 1.27 1.27)
				)
			)
		)
		(property "Footprint" ""
			(at 294.64 108.585 0)
			(effects
				(font
					(size 1.27 1.27)
					(thickness 0.15)
				)
				(justify left bottom)
				(hide yes)
			)
		)
		(property "Datasheet" ""
			(at 294.64 111.125 0)
			(effects
				(font
					(size 1.27 1.27)
					(thickness 0.15)
				)
				(justify left bottom)
				(hide yes)
			)
		)
		(property "Description" ""
			(at 279.4 100.965 0)
			(effects
				(font
					(size 1.27 1.27)
				)
			)
		)
		(property "Author" "Antmicro"
			(at 294.64 108.585 0)
			(effects
				(font
					(size 1.27 1.27)
					(thickness 0.15)
				)
				(justify left bottom)
				(hide yes)
			)
		)
		(property "License" "Apache-2.0"
			(at 294.64 111.125 0)
			(effects
				(font
					(size 1.27 1.27)
					(thickness 0.15)
				)
				(justify left bottom)
				(hide yes)
			)
		)
		(pin "1"
		)
		(instances
			(project "k410t-devboard"
				(path ""
					(reference "#PWR0165")
					(unit 1)
				)
			)
		)
	)
	(symbol
		(lib_id "antmicropower:GND")
		(at 186.69 175.26 0)
		(unit 1)
		(exclude_from_sim no)
		(in_bom yes)
		(on_board yes)
		(dnp no)
		(property "Reference" "#PWR0171"
			(at 186.69 181.61 0)
			(effects
				(font
					(size 1.27 1.27)
				)
				(hide yes)
			)
		)
		(property "Value" "GND"
			(at 186.69 179.07 0)
			(effects
				(font
					(size 1.27 1.27)
				)
			)
		)
		(property "Footprint" ""
			(at 195.58 182.88 0)
			(effects
				(font
					(size 1.27 1.27)
					(thickness 0.15)
				)
				(justify left bottom)
				(hide yes)
			)
		)
		(property "Datasheet" ""
			(at 195.58 187.96 0)
			(effects
				(font
					(size 1.27 1.27)
					(thickness 0.15)
				)
				(justify left bottom)
				(hide yes)
			)
		)
		(property "Description" ""
			(at 186.69 175.26 0)
			(effects
				(font
					(size 1.27 1.27)
				)
			)
		)
		(property "Author" "Antmicro"
			(at 195.58 182.88 0)
			(effects
				(font
					(size 1.27 1.27)
					(thickness 0.15)
				)
				(justify left bottom)
				(hide yes)
			)
		)
		(property "License" "Apache-2.0"
			(at 195.58 185.42 0)
			(effects
				(font
					(size 1.27 1.27)
					(thickness 0.15)
				)
				(justify left bottom)
				(hide yes)
			)
		)
		(pin "1"
		)
		(instances
			(project "k410t-devboard"
				(path ""
					(reference "#PWR0171")
					(unit 1)
				)
			)
		)
	)
	(symbol
		(lib_id "antmicropower:+3.3V")
		(at 111.76 50.8 0)
		(unit 1)
		(exclude_from_sim no)
		(in_bom yes)
		(on_board yes)
		(dnp no)
		(fields_autoplaced yes)
		(property "Reference" "#PWR0142"
			(at 111.76 54.61 0)
			(effects
				(font
					(size 1.27 1.27)
				)
				(hide yes)
			)
		)
		(property "Value" "+3V3"
			(at 111.76 47.244 0)
			(effects
				(font
					(size 1.27 1.27)
				)
			)
		)
		(property "Footprint" ""
			(at 111.76 50.8 0)
			(effects
				(font
					(size 1.27 1.27)
				)
				(hide yes)
			)
		)
		(property "Datasheet" ""
			(at 111.76 50.8 0)
			(effects
				(font
					(size 1.27 1.27)
				)
				(hide yes)
			)
		)
		(property "Description" ""
			(at 111.76 50.8 0)
			(effects
				(font
					(size 1.27 1.27)
				)
			)
		)
		(pin "1"
		)
		(instances
			(project "k410t-devboard"
				(path ""
					(reference "#PWR0142")
					(unit 1)
				)
			)
		)
	)
	(symbol
		(lib_id "antmicropower:+3.3V")
		(at 132.08 207.01 0)
		(unit 1)
		(exclude_from_sim no)
		(in_bom yes)
		(on_board yes)
		(dnp no)
		(fields_autoplaced yes)
		(property "Reference" "#PWR0154"
			(at 132.08 210.82 0)
			(effects
				(font
					(size 1.27 1.27)
				)
				(hide yes)
			)
		)
		(property "Value" "+3V3"
			(at 132.08 203.454 0)
			(effects
				(font
					(size 1.27 1.27)
				)
			)
		)
		(property "Footprint" ""
			(at 132.08 207.01 0)
			(effects
				(font
					(size 1.27 1.27)
				)
				(hide yes)
			)
		)
		(property "Datasheet" ""
			(at 132.08 207.01 0)
			(effects
				(font
					(size 1.27 1.27)
				)
				(hide yes)
			)
		)
		(property "Description" ""
			(at 132.08 207.01 0)
			(effects
				(font
					(size 1.27 1.27)
				)
			)
		)
		(pin "1"
		)
		(instances
			(project "k410t-devboard"
				(path ""
					(reference "#PWR0154")
					(unit 1)
				)
			)
		)
	)
	(symbol
		(lib_id "antmicropower:GND")
		(at 328.93 96.52 0)
		(unit 1)
		(exclude_from_sim no)
		(in_bom yes)
		(on_board yes)
		(dnp no)
		(property "Reference" "#PWR0191"
			(at 328.93 102.87 0)
			(effects
				(font
					(size 1.27 1.27)
				)
				(hide yes)
			)
		)
		(property "Value" "GND"
			(at 328.93 100.33 0)
			(effects
				(font
					(size 1.27 1.27)
				)
			)
		)
		(property "Footprint" ""
			(at 337.82 104.14 0)
			(effects
				(font
					(size 1.27 1.27)
					(thickness 0.15)
				)
				(justify left bottom)
				(hide yes)
			)
		)
		(property "Datasheet" ""
			(at 337.82 109.22 0)
			(effects
				(font
					(size 1.27 1.27)
					(thickness 0.15)
				)
				(justify left bottom)
				(hide yes)
			)
		)
		(property "Description" ""
			(at 328.93 96.52 0)
			(effects
				(font
					(size 1.27 1.27)
				)
			)
		)
		(property "Author" "Antmicro"
			(at 337.82 104.14 0)
			(effects
				(font
					(size 1.27 1.27)
					(thickness 0.15)
				)
				(justify left bottom)
				(hide yes)
			)
		)
		(property "License" "Apache-2.0"
			(at 337.82 106.68 0)
			(effects
				(font
					(size 1.27 1.27)
					(thickness 0.15)
				)
				(justify left bottom)
				(hide yes)
			)
		)
		(pin "1"
		)
		(instances
			(project "k410t-devboard"
				(path ""
					(reference "#PWR0191")
					(unit 1)
				)
			)
		)
	)
	(symbol
		(lib_id "antmicroResistors0402:R_100k_0402")
		(at 190.5 201.93 0)
		(unit 1)
		(exclude_from_sim no)
		(in_bom yes)
		(on_board yes)
		(dnp no)
		(property "Reference" "R359"
			(at 193.04 196.85 0)
			(effects
				(font
					(size 1.27 1.27)
				)
			)
		)
		(property "Value" "R_100k_0402"
			(at 210.82 214.63 0)
			(effects
				(font
					(size 1.27 1.27)
					(thickness 0.15)
				)
				(justify left bottom)
				(hide yes)
			)
		)
		(property "Footprint" "antmicro-footprints:R_0402_1005Metric"
			(at 210.82 217.17 0)
			(effects
				(font
					(size 1.27 1.27)
					(thickness 0.15)
				)
				(justify left bottom)
				(hide yes)
			)
		)
		(property "Datasheet" "https://www.bourns.com/docs/product-datasheets/cr.pdf"
			(at 210.82 219.71 0)
			(effects
				(font
					(size 1.27 1.27)
					(thickness 0.15)
				)
				(justify left bottom)
				(hide yes)
			)
		)
		(property "Description" ""
			(at 190.5 201.93 0)
			(effects
				(font
					(size 1.27 1.27)
				)
			)
		)
		(property "Manufacturer" "Bourns"
			(at 210.82 224.79 0)
			(effects
				(font
					(size 1.27 1.27)
					(thickness 0.15)
				)
				(justify left bottom)
				(hide yes)
			)
		)
		(property "MPN" "CR0402-FX-1003GLF"
			(at 210.82 222.25 0)
			(effects
				(font
					(size 1.27 1.27)
					(thickness 0.15)
				)
				(justify left bottom)
				(hide yes)
			)
		)
		(property "Val" "100k"
			(at 193.04 199.39 0)
			(effects
				(font
					(size 1.27 1.27)
					(thickness 0.15)
				)
			)
		)
		(property "License" "Apache-2.0"
			(at 210.82 227.33 0)
			(effects
				(font
					(size 1.27 1.27)
					(thickness 0.15)
				)
				(justify left bottom)
				(hide yes)
			)
		)
		(property "Author" "Antmicro"
			(at 210.82 229.87 0)
			(effects
				(font
					(size 1.27 1.27)
					(thickness 0.15)
				)
				(justify left bottom)
				(hide yes)
			)
		)
		(property "Tolerance" "1%"
			(at 210.82 212.09 0)
			(effects
				(font
					(size 1.27 1.27)
				)
				(justify left bottom)
				(hide yes)
			)
		)
		(pin "1"
		)
		(pin "2"
		)
		(instances
			(project "k410t-devboard"
				(path ""
					(reference "R359")
					(unit 1)
				)
			)
		)
	)
	(symbol
		(lib_id "antmicroResistors0402:R_100R_0402")
		(at 87.63 87.63 180)
		(unit 1)
		(exclude_from_sim no)
		(in_bom yes)
		(on_board yes)
		(dnp no)
		(property "Reference" "R116"
			(at 90.17 86.36 0)
			(effects
				(font
					(size 1.27 1.27)
				)
			)
		)
		(property "Value" "R_100R_0402"
			(at 67.31 74.93 0)
			(effects
				(font
					(size 1.27 1.27)
					(thickness 0.15)
				)
				(justify left bottom)
				(hide yes)
			)
		)
		(property "Footprint" "antmicro-footprints:R_0402_1005Metric"
			(at 67.31 72.39 0)
			(effects
				(font
					(size 1.27 1.27)
					(thickness 0.15)
				)
				(justify left bottom)
				(hide yes)
			)
		)
		(property "Datasheet" "https://www.bourns.com/docs/product-datasheets/cr.pdf"
			(at 67.31 69.85 0)
			(effects
				(font
					(size 1.27 1.27)
					(thickness 0.15)
				)
				(justify left bottom)
				(hide yes)
			)
		)
		(property "Description" ""
			(at 87.63 87.63 0)
			(effects
				(font
					(size 1.27 1.27)
				)
			)
		)
		(property "Manufacturer" "Bourns"
			(at 67.31 64.77 0)
			(effects
				(font
					(size 1.27 1.27)
					(thickness 0.15)
				)
				(justify left bottom)
				(hide yes)
			)
		)
		(property "MPN" "CR0402-FX-1000GLF"
			(at 67.31 67.31 0)
			(effects
				(font
					(size 1.27 1.27)
					(thickness 0.15)
				)
				(justify left bottom)
				(hide yes)
			)
		)
		(property "Val" "100R"
			(at 80.01 86.36 0)
			(effects
				(font
					(size 1.27 1.27)
					(thickness 0.15)
				)
			)
		)
		(property "License" "Apache-2.0"
			(at 67.31 62.23 0)
			(effects
				(font
					(size 1.27 1.27)
					(thickness 0.15)
				)
				(justify left bottom)
				(hide yes)
			)
		)
		(property "Author" "Antmicro"
			(at 67.31 59.69 0)
			(effects
				(font
					(size 1.27 1.27)
					(thickness 0.15)
				)
				(justify left bottom)
				(hide yes)
			)
		)
		(property "Tolerance" "1%"
			(at 67.31 77.47 0)
			(effects
				(font
					(size 1.27 1.27)
				)
				(justify left bottom)
				(hide yes)
			)
		)
		(pin "1"
		)
		(pin "2"
		)
		(instances
			(project "k410t-devboard"
				(path ""
					(reference "R116")
					(unit 1)
				)
			)
		)
	)
	(symbol
		(lib_id "antmicroResistors0402:R_1k_0402")
		(at 54.61 154.94 0)
		(unit 1)
		(exclude_from_sim no)
		(in_bom yes)
		(on_board yes)
		(dnp no)
		(property "Reference" "R107"
			(at 57.15 149.86 0)
			(effects
				(font
					(size 1.27 1.27)
				)
			)
		)
		(property "Value" "R_1k_0402"
			(at 74.93 167.64 0)
			(effects
				(font
					(size 1.27 1.27)
					(thickness 0.15)
				)
				(justify left bottom)
				(hide yes)
			)
		)
		(property "Footprint" "antmicro-footprints:R_0402_1005Metric"
			(at 74.93 170.18 0)
			(effects
				(font
					(size 1.27 1.27)
					(thickness 0.15)
				)
				(justify left bottom)
				(hide yes)
			)
		)
		(property "Datasheet" "https://www.bourns.com/docs/product-datasheets/cr.pdf"
			(at 74.93 172.72 0)
			(effects
				(font
					(size 1.27 1.27)
					(thickness 0.15)
				)
				(justify left bottom)
				(hide yes)
			)
		)
		(property "Description" ""
			(at 54.61 154.94 0)
			(effects
				(font
					(size 1.27 1.27)
				)
			)
		)
		(property "Manufacturer" "Bourns"
			(at 74.93 177.8 0)
			(effects
				(font
					(size 1.27 1.27)
					(thickness 0.15)
				)
				(justify left bottom)
				(hide yes)
			)
		)
		(property "MPN" "CR0402-FX-1001GLF"
			(at 74.93 175.26 0)
			(effects
				(font
					(size 1.27 1.27)
					(thickness 0.15)
				)
				(justify left bottom)
				(hide yes)
			)
		)
		(property "Val" "1k"
			(at 57.15 152.4 0)
			(effects
				(font
					(size 1.27 1.27)
					(thickness 0.15)
				)
			)
		)
		(property "License" "Apache-2.0"
			(at 74.93 180.34 0)
			(effects
				(font
					(size 1.27 1.27)
					(thickness 0.15)
				)
				(justify left bottom)
				(hide yes)
			)
		)
		(property "Author" "Antmicro"
			(at 74.93 182.88 0)
			(effects
				(font
					(size 1.27 1.27)
					(thickness 0.15)
				)
				(justify left bottom)
				(hide yes)
			)
		)
		(property "Tolerance" "1%"
			(at 74.93 165.1 0)
			(effects
				(font
					(size 1.27 1.27)
				)
				(justify left bottom)
				(hide yes)
			)
		)
		(pin "1"
		)
		(pin "2"
		)
		(instances
			(project "k410t-devboard"
				(path ""
					(reference "R107")
					(unit 1)
				)
			)
		)
	)
	(symbol
		(lib_id "antmicroResistors0402:R_100R_0402")
		(at 87.63 95.25 180)
		(unit 1)
		(exclude_from_sim no)
		(in_bom yes)
		(on_board yes)
		(dnp no)
		(property "Reference" "R119"
			(at 90.17 93.98 0)
			(effects
				(font
					(size 1.27 1.27)
				)
			)
		)
		(property "Value" "R_100R_0402"
			(at 67.31 82.55 0)
			(effects
				(font
					(size 1.27 1.27)
					(thickness 0.15)
				)
				(justify left bottom)
				(hide yes)
			)
		)
		(property "Footprint" "antmicro-footprints:R_0402_1005Metric"
			(at 67.31 80.01 0)
			(effects
				(font
					(size 1.27 1.27)
					(thickness 0.15)
				)
				(justify left bottom)
				(hide yes)
			)
		)
		(property "Datasheet" "https://www.bourns.com/docs/product-datasheets/cr.pdf"
			(at 67.31 77.47 0)
			(effects
				(font
					(size 1.27 1.27)
					(thickness 0.15)
				)
				(justify left bottom)
				(hide yes)
			)
		)
		(property "Description" ""
			(at 87.63 95.25 0)
			(effects
				(font
					(size 1.27 1.27)
				)
			)
		)
		(property "Manufacturer" "Bourns"
			(at 67.31 72.39 0)
			(effects
				(font
					(size 1.27 1.27)
					(thickness 0.15)
				)
				(justify left bottom)
				(hide yes)
			)
		)
		(property "MPN" "CR0402-FX-1000GLF"
			(at 67.31 74.93 0)
			(effects
				(font
					(size 1.27 1.27)
					(thickness 0.15)
				)
				(justify left bottom)
				(hide yes)
			)
		)
		(property "Val" "100R"
			(at 80.01 93.98 0)
			(effects
				(font
					(size 1.27 1.27)
					(thickness 0.15)
				)
			)
		)
		(property "License" "Apache-2.0"
			(at 67.31 69.85 0)
			(effects
				(font
					(size 1.27 1.27)
					(thickness 0.15)
				)
				(justify left bottom)
				(hide yes)
			)
		)
		(property "Author" "Antmicro"
			(at 67.31 67.31 0)
			(effects
				(font
					(size 1.27 1.27)
					(thickness 0.15)
				)
				(justify left bottom)
				(hide yes)
			)
		)
		(property "Tolerance" "1%"
			(at 67.31 85.09 0)
			(effects
				(font
					(size 1.27 1.27)
				)
				(justify left bottom)
				(hide yes)
			)
		)
		(pin "1"
		)
		(pin "2"
		)
		(instances
			(project "k410t-devboard"
				(path ""
					(reference "R119")
					(unit 1)
				)
			)
		)
	)
	(symbol
		(lib_id "antmicropower:GND")
		(at 306.07 115.57 0)
		(unit 1)
		(exclude_from_sim no)
		(in_bom yes)
		(on_board yes)
		(dnp no)
		(property "Reference" "#PWR0188"
			(at 306.07 121.92 0)
			(effects
				(font
					(size 1.27 1.27)
				)
				(hide yes)
			)
		)
		(property "Value" "GND"
			(at 306.07 119.38 0)
			(effects
				(font
					(size 1.27 1.27)
				)
			)
		)
		(property "Footprint" ""
			(at 314.96 123.19 0)
			(effects
				(font
					(size 1.27 1.27)
					(thickness 0.15)
				)
				(justify left bottom)
				(hide yes)
			)
		)
		(property "Datasheet" ""
			(at 314.96 128.27 0)
			(effects
				(font
					(size 1.27 1.27)
					(thickness 0.15)
				)
				(justify left bottom)
				(hide yes)
			)
		)
		(property "Description" ""
			(at 306.07 115.57 0)
			(effects
				(font
					(size 1.27 1.27)
				)
			)
		)
		(property "Author" "Antmicro"
			(at 314.96 123.19 0)
			(effects
				(font
					(size 1.27 1.27)
					(thickness 0.15)
				)
				(justify left bottom)
				(hide yes)
			)
		)
		(property "License" "Apache-2.0"
			(at 314.96 125.73 0)
			(effects
				(font
					(size 1.27 1.27)
					(thickness 0.15)
				)
				(justify left bottom)
				(hide yes)
			)
		)
		(pin "1"
		)
		(instances
			(project "k410t-devboard"
				(path ""
					(reference "#PWR0188")
					(unit 1)
				)
			)
		)
	)
	(symbol
		(lib_id "antmicroResistors0402:R_100R_0402")
		(at 356.87 40.64 180)
		(unit 1)
		(exclude_from_sim no)
		(in_bom yes)
		(on_board yes)
		(dnp no)
		(property "Reference" "R144"
			(at 359.41 39.37 0)
			(effects
				(font
					(size 1.27 1.27)
				)
			)
		)
		(property "Value" "R_100R_0402"
			(at 336.55 27.94 0)
			(effects
				(font
					(size 1.27 1.27)
					(thickness 0.15)
				)
				(justify left bottom)
				(hide yes)
			)
		)
		(property "Footprint" "antmicro-footprints:R_0402_1005Metric"
			(at 336.55 25.4 0)
			(effects
				(font
					(size 1.27 1.27)
					(thickness 0.15)
				)
				(justify left bottom)
				(hide yes)
			)
		)
		(property "Datasheet" "https://www.bourns.com/docs/product-datasheets/cr.pdf"
			(at 336.55 22.86 0)
			(effects
				(font
					(size 1.27 1.27)
					(thickness 0.15)
				)
				(justify left bottom)
				(hide yes)
			)
		)
		(property "Description" ""
			(at 356.87 40.64 0)
			(effects
				(font
					(size 1.27 1.27)
				)
			)
		)
		(property "Manufacturer" "Bourns"
			(at 336.55 17.78 0)
			(effects
				(font
					(size 1.27 1.27)
					(thickness 0.15)
				)
				(justify left bottom)
				(hide yes)
			)
		)
		(property "MPN" "CR0402-FX-1000GLF"
			(at 336.55 20.32 0)
			(effects
				(font
					(size 1.27 1.27)
					(thickness 0.15)
				)
				(justify left bottom)
				(hide yes)
			)
		)
		(property "Val" "100R"
			(at 349.25 39.37 0)
			(effects
				(font
					(size 1.27 1.27)
					(thickness 0.15)
				)
			)
		)
		(property "License" "Apache-2.0"
			(at 336.55 15.24 0)
			(effects
				(font
					(size 1.27 1.27)
					(thickness 0.15)
				)
				(justify left bottom)
				(hide yes)
			)
		)
		(property "Author" "Antmicro"
			(at 336.55 12.7 0)
			(effects
				(font
					(size 1.27 1.27)
					(thickness 0.15)
				)
				(justify left bottom)
				(hide yes)
			)
		)
		(property "Tolerance" "1%"
			(at 336.55 30.48 0)
			(effects
				(font
					(size 1.27 1.27)
				)
				(justify left bottom)
				(hide yes)
			)
		)
		(pin "1"
		)
		(pin "2"
		)
		(instances
			(project "k410t-devboard"
				(path ""
					(reference "R144")
					(unit 1)
				)
			)
		)
	)
	(symbol
		(lib_id "antmicroPushbuttonSwitches:SW_KMR211NGLFS_SMD")
		(at 289.56 110.49 0)
		(unit 1)
		(exclude_from_sim no)
		(in_bom yes)
		(on_board yes)
		(dnp no)
		(fields_autoplaced yes)
		(property "Reference" "S3"
			(at 294.64 115.57 0)
			(effects
				(font
					(size 1.27 1.27)
				)
			)
		)
		(property "Value" "SW_KMR211NGLFS_SMD"
			(at 294.64 114.935 0)
			(effects
				(font
					(size 1.27 1.27)
					(thickness 0.15)
				)
				(hide yes)
			)
		)
		(property "Footprint" "antmicro-footprints:SW_KMR211NGLFS_SMD"
			(at 314.96 118.11 0)
			(effects
				(font
					(size 1.27 1.27)
					(thickness 0.15)
				)
				(justify left bottom)
				(hide yes)
			)
		)
		(property "Datasheet" "http://www.farnell.com/datasheets/2631211.pdf"
			(at 314.96 120.65 0)
			(effects
				(font
					(size 1.27 1.27)
					(thickness 0.15)
				)
				(justify left bottom)
				(hide yes)
			)
		)
		(property "Description" ""
			(at 289.56 110.49 0)
			(effects
				(font
					(size 1.27 1.27)
				)
			)
		)
		(property "MPN" "KMR211NGLFS"
			(at 294.64 118.11 0)
			(effects
				(font
					(size 1.27 1.27)
					(thickness 0.15)
				)
			)
		)
		(property "Manufacturer" "C&K"
			(at 314.96 125.73 0)
			(effects
				(font
					(size 1.27 1.27)
					(thickness 0.15)
				)
				(justify left bottom)
				(hide yes)
			)
		)
		(property "Author" "Antmicro"
			(at 314.96 128.27 0)
			(effects
				(font
					(size 1.27 1.27)
					(thickness 0.15)
				)
				(justify left bottom)
				(hide yes)
			)
		)
		(property "License" "Apache-2.0"
			(at 314.96 130.81 0)
			(effects
				(font
					(size 1.27 1.27)
					(thickness 0.15)
				)
				(justify left bottom)
				(hide yes)
			)
		)
		(pin "1"
		)
		(pin "2"
		)
		(pin "3"
		)
		(pin "4"
		)
		(instances
			(project "k410t-devboard"
				(path ""
					(reference "S3")
					(unit 1)
				)
			)
		)
	)
	(symbol
		(lib_id "antmicropower:GND")
		(at 111.76 119.38 0)
		(unit 1)
		(exclude_from_sim no)
		(in_bom yes)
		(on_board yes)
		(dnp no)
		(property "Reference" "#PWR0148"
			(at 111.76 125.73 0)
			(effects
				(font
					(size 1.27 1.27)
				)
				(hide yes)
			)
		)
		(property "Value" "GND"
			(at 111.76 123.19 0)
			(effects
				(font
					(size 1.27 1.27)
				)
			)
		)
		(property "Footprint" ""
			(at 120.65 127 0)
			(effects
				(font
					(size 1.27 1.27)
					(thickness 0.15)
				)
				(justify left bottom)
				(hide yes)
			)
		)
		(property "Datasheet" ""
			(at 120.65 132.08 0)
			(effects
				(font
					(size 1.27 1.27)
					(thickness 0.15)
				)
				(justify left bottom)
				(hide yes)
			)
		)
		(property "Description" ""
			(at 111.76 119.38 0)
			(effects
				(font
					(size 1.27 1.27)
				)
			)
		)
		(property "Author" "Antmicro"
			(at 120.65 127 0)
			(effects
				(font
					(size 1.27 1.27)
					(thickness 0.15)
				)
				(justify left bottom)
				(hide yes)
			)
		)
		(property "License" "Apache-2.0"
			(at 120.65 129.54 0)
			(effects
				(font
					(size 1.27 1.27)
					(thickness 0.15)
				)
				(justify left bottom)
				(hide yes)
			)
		)
		(pin "1"
		)
		(instances
			(project "k410t-devboard"
				(path ""
					(reference "#PWR0148")
					(unit 1)
				)
			)
		)
	)
	(symbol
		(lib_id "antmicroWire2BoardConnectors:JST_SH_1x4_BM04B-SRSS-TB-LF-SN")
		(at 97.79 250.19 0)
		(unit 1)
		(exclude_from_sim no)
		(in_bom yes)
		(on_board yes)
		(dnp no)
		(property "Reference" "J4"
			(at 96.52 245.11 0)
			(effects
				(font
					(size 1.27 1.27)
					(thickness 0.15)
				)
				(justify left)
			)
		)
		(property "Value" "JST_SH_1x4_BM04B-SRSS-TB-LF-SN"
			(at 118.11 257.81 0)
			(effects
				(font
					(size 1.27 1.27)
					(thickness 0.15)
				)
				(justify left bottom)
				(hide yes)
			)
		)
		(property "Footprint" "antmicro-footprints:Conn_JST_SH_1x4_BM04B-SRSS-TB-LF-SN"
			(at 118.11 260.35 0)
			(effects
				(font
					(size 1.27 1.27)
					(thickness 0.15)
				)
				(justify left bottom)
				(hide yes)
			)
		)
		(property "Datasheet" "https://www.jst-mfg.com/product/pdf/eng/eSH.pdf"
			(at 118.11 262.89 0)
			(effects
				(font
					(size 1.27 1.27)
					(thickness 0.15)
				)
				(justify left bottom)
				(hide yes)
			)
		)
		(property "Description" ""
			(at 97.79 250.19 0)
			(effects
				(font
					(size 1.27 1.27)
				)
			)
		)
		(property "MPN" "BM04B-SRSS-TB(LF)(SN) "
			(at 96.52 247.65 0)
			(effects
				(font
					(size 1.27 1.27)
					(thickness 0.15)
				)
				(justify left)
			)
		)
		(property "Manufacturer" "JST Automotive Connectors"
			(at 118.11 267.97 0)
			(effects
				(font
					(size 1.27 1.27)
					(thickness 0.15)
				)
				(justify left bottom)
				(hide yes)
			)
		)
		(property "Author" "Antmicro"
			(at 118.11 270.51 0)
			(effects
				(font
					(size 1.27 1.27)
					(thickness 0.15)
				)
				(justify left bottom)
				(hide yes)
			)
		)
		(property "License" "Apache-2.0"
			(at 118.11 273.05 0)
			(effects
				(font
					(size 1.27 1.27)
					(thickness 0.15)
				)
				(justify left bottom)
				(hide yes)
			)
		)
		(pin "1"
		)
		(pin "2"
		)
		(pin "3"
		)
		(pin "4"
		)
		(pin "MP"
		)
		(instances
			(project "k410t-devboard"
				(path ""
					(reference "J4")
					(unit 1)
				)
			)
		)
	)
	(symbol
		(lib_id "antmicroResistors0402:R_100R_0402")
		(at 356.87 48.26 180)
		(unit 1)
		(exclude_from_sim no)
		(in_bom yes)
		(on_board yes)
		(dnp no)
		(property "Reference" "R147"
			(at 359.41 46.99 0)
			(effects
				(font
					(size 1.27 1.27)
				)
			)
		)
		(property "Value" "R_100R_0402"
			(at 336.55 35.56 0)
			(effects
				(font
					(size 1.27 1.27)
					(thickness 0.15)
				)
				(justify left bottom)
				(hide yes)
			)
		)
		(property "Footprint" "antmicro-footprints:R_0402_1005Metric"
			(at 336.55 33.02 0)
			(effects
				(font
					(size 1.27 1.27)
					(thickness 0.15)
				)
				(justify left bottom)
				(hide yes)
			)
		)
		(property "Datasheet" "https://www.bourns.com/docs/product-datasheets/cr.pdf"
			(at 336.55 30.48 0)
			(effects
				(font
					(size 1.27 1.27)
					(thickness 0.15)
				)
				(justify left bottom)
				(hide yes)
			)
		)
		(property "Description" ""
			(at 356.87 48.26 0)
			(effects
				(font
					(size 1.27 1.27)
				)
			)
		)
		(property "Manufacturer" "Bourns"
			(at 336.55 25.4 0)
			(effects
				(font
					(size 1.27 1.27)
					(thickness 0.15)
				)
				(justify left bottom)
				(hide yes)
			)
		)
		(property "MPN" "CR0402-FX-1000GLF"
			(at 336.55 27.94 0)
			(effects
				(font
					(size 1.27 1.27)
					(thickness 0.15)
				)
				(justify left bottom)
				(hide yes)
			)
		)
		(property "Val" "100R"
			(at 349.25 46.99 0)
			(effects
				(font
					(size 1.27 1.27)
					(thickness 0.15)
				)
			)
		)
		(property "License" "Apache-2.0"
			(at 336.55 22.86 0)
			(effects
				(font
					(size 1.27 1.27)
					(thickness 0.15)
				)
				(justify left bottom)
				(hide yes)
			)
		)
		(property "Author" "Antmicro"
			(at 336.55 20.32 0)
			(effects
				(font
					(size 1.27 1.27)
					(thickness 0.15)
				)
				(justify left bottom)
				(hide yes)
			)
		)
		(property "Tolerance" "1%"
			(at 336.55 38.1 0)
			(effects
				(font
					(size 1.27 1.27)
				)
				(justify left bottom)
				(hide yes)
			)
		)
		(pin "1"
		)
		(pin "2"
		)
		(instances
			(project "k410t-devboard"
				(path ""
					(reference "R147")
					(unit 1)
				)
			)
		)
	)
	(symbol
		(lib_id "antmicroResistors0402:R_100R_0402")
		(at 140.97 33.02 180)
		(unit 1)
		(exclude_from_sim no)
		(in_bom yes)
		(on_board yes)
		(dnp no)
		(property "Reference" "R121"
			(at 143.51 31.75 0)
			(effects
				(font
					(size 1.27 1.27)
				)
			)
		)
		(property "Value" "R_100R_0402"
			(at 120.65 20.32 0)
			(effects
				(font
					(size 1.27 1.27)
					(thickness 0.15)
				)
				(justify left bottom)
				(hide yes)
			)
		)
		(property "Footprint" "antmicro-footprints:R_0402_1005Metric"
			(at 120.65 17.78 0)
			(effects
				(font
					(size 1.27 1.27)
					(thickness 0.15)
				)
				(justify left bottom)
				(hide yes)
			)
		)
		(property "Datasheet" "https://www.bourns.com/docs/product-datasheets/cr.pdf"
			(at 120.65 15.24 0)
			(effects
				(font
					(size 1.27 1.27)
					(thickness 0.15)
				)
				(justify left bottom)
				(hide yes)
			)
		)
		(property "Description" ""
			(at 140.97 33.02 0)
			(effects
				(font
					(size 1.27 1.27)
				)
			)
		)
		(property "Manufacturer" "Bourns"
			(at 120.65 10.16 0)
			(effects
				(font
					(size 1.27 1.27)
					(thickness 0.15)
				)
				(justify left bottom)
				(hide yes)
			)
		)
		(property "MPN" "CR0402-FX-1000GLF"
			(at 120.65 12.7 0)
			(effects
				(font
					(size 1.27 1.27)
					(thickness 0.15)
				)
				(justify left bottom)
				(hide yes)
			)
		)
		(property "Val" "100R"
			(at 133.35 31.75 0)
			(effects
				(font
					(size 1.27 1.27)
					(thickness 0.15)
				)
			)
		)
		(property "License" "Apache-2.0"
			(at 120.65 7.62 0)
			(effects
				(font
					(size 1.27 1.27)
					(thickness 0.15)
				)
				(justify left bottom)
				(hide yes)
			)
		)
		(property "Author" "Antmicro"
			(at 120.65 5.08 0)
			(effects
				(font
					(size 1.27 1.27)
					(thickness 0.15)
				)
				(justify left bottom)
				(hide yes)
			)
		)
		(property "Tolerance" "1%"
			(at 120.65 22.86 0)
			(effects
				(font
					(size 1.27 1.27)
				)
				(justify left bottom)
				(hide yes)
			)
		)
		(pin "1"
		)
		(pin "2"
		)
		(instances
			(project "k410t-devboard"
				(path ""
					(reference "R121")
					(unit 1)
				)
			)
		)
	)
	(symbol
		(lib_id "antmicropower:GND")
		(at 186.69 156.21 0)
		(unit 1)
		(exclude_from_sim no)
		(in_bom yes)
		(on_board yes)
		(dnp no)
		(property "Reference" "#PWR0170"
			(at 186.69 162.56 0)
			(effects
				(font
					(size 1.27 1.27)
				)
				(hide yes)
			)
		)
		(property "Value" "GND"
			(at 186.69 160.02 0)
			(effects
				(font
					(size 1.27 1.27)
				)
			)
		)
		(property "Footprint" ""
			(at 195.58 163.83 0)
			(effects
				(font
					(size 1.27 1.27)
					(thickness 0.15)
				)
				(justify left bottom)
				(hide yes)
			)
		)
		(property "Datasheet" ""
			(at 195.58 168.91 0)
			(effects
				(font
					(size 1.27 1.27)
					(thickness 0.15)
				)
				(justify left bottom)
				(hide yes)
			)
		)
		(property "Description" ""
			(at 186.69 156.21 0)
			(effects
				(font
					(size 1.27 1.27)
				)
			)
		)
		(property "Author" "Antmicro"
			(at 195.58 163.83 0)
			(effects
				(font
					(size 1.27 1.27)
					(thickness 0.15)
				)
				(justify left bottom)
				(hide yes)
			)
		)
		(property "License" "Apache-2.0"
			(at 195.58 166.37 0)
			(effects
				(font
					(size 1.27 1.27)
					(thickness 0.15)
				)
				(justify left bottom)
				(hide yes)
			)
		)
		(pin "1"
		)
		(instances
			(project "k410t-devboard"
				(path ""
					(reference "#PWR0170")
					(unit 1)
				)
			)
		)
	)
	(symbol
		(lib_id "antmicroTransistorsFETsMOSFETsSingle:BSS138PW")
		(at 96.52 219.71 90)
		(unit 1)
		(exclude_from_sim no)
		(in_bom yes)
		(on_board yes)
		(dnp no)
		(fields_autoplaced yes)
		(property "Reference" "Q11"
			(at 93.98 205.105 90)
			(effects
				(font
					(size 1.27 1.27)
				)
			)
		)
		(property "Value" "BSS138PW"
			(at 93.98 207.645 90)
			(effects
				(font
					(size 1.27 1.27)
					(thickness 0.15)
				)
			)
		)
		(property "Footprint" "antmicro-footprints:SC70-3"
			(at 107.95 196.85 0)
			(effects
				(font
					(size 1.27 1.27)
					(thickness 0.15)
				)
				(justify left bottom)
				(hide yes)
			)
		)
		(property "Datasheet" "https://assets.nexperia.com/documents/data-sheet/BSS138PW.pdf"
			(at 110.49 196.85 0)
			(effects
				(font
					(size 1.27 1.27)
					(thickness 0.15)
				)
				(justify left bottom)
				(hide yes)
			)
		)
		(property "Description" ""
			(at 96.52 219.71 0)
			(effects
				(font
					(size 1.27 1.27)
				)
			)
		)
		(property "MPN" "BSS138PW"
			(at 113.03 196.85 0)
			(effects
				(font
					(size 1.27 1.27)
					(thickness 0.15)
				)
				(justify left bottom)
				(hide yes)
			)
		)
		(property "Manufacturer" "Nexperia"
			(at 115.57 196.85 0)
			(effects
				(font
					(size 1.27 1.27)
					(thickness 0.15)
				)
				(justify left bottom)
				(hide yes)
			)
		)
		(property "Author" "Antmicro"
			(at 118.11 196.85 0)
			(effects
				(font
					(size 1.27 1.27)
					(thickness 0.15)
				)
				(justify left bottom)
				(hide yes)
			)
		)
		(property "License" "Apache-2.0"
			(at 120.65 196.85 0)
			(effects
				(font
					(size 1.27 1.27)
					(thickness 0.15)
				)
				(justify left bottom)
				(hide yes)
			)
		)
		(pin "1"
		)
		(pin "2"
		)
		(pin "3"
		)
		(instances
			(project "k410t-devboard"
				(path ""
					(reference "Q11")
					(unit 1)
				)
			)
		)
	)
	(symbol
		(lib_id "antmicroPushbuttonSwitches:SW_KMR211NGLFS_SMD")
		(at 312.42 91.44 0)
		(unit 1)
		(exclude_from_sim no)
		(in_bom yes)
		(on_board yes)
		(dnp no)
		(fields_autoplaced yes)
		(property "Reference" "S2"
			(at 317.5 83.82 0)
			(effects
				(font
					(size 1.27 1.27)
				)
			)
		)
		(property "Value" "SW_KMR211NGLFS_SMD"
			(at 317.5 95.885 0)
			(effects
				(font
					(size 1.27 1.27)
					(thickness 0.15)
				)
				(hide yes)
			)
		)
		(property "Footprint" "antmicro-footprints:SW_KMR211NGLFS_SMD"
			(at 337.82 99.06 0)
			(effects
				(font
					(size 1.27 1.27)
					(thickness 0.15)
				)
				(justify left bottom)
				(hide yes)
			)
		)
		(property "Datasheet" "http://www.farnell.com/datasheets/2631211.pdf"
			(at 337.82 101.6 0)
			(effects
				(font
					(size 1.27 1.27)
					(thickness 0.15)
				)
				(justify left bottom)
				(hide yes)
			)
		)
		(property "Description" ""
			(at 312.42 91.44 0)
			(effects
				(font
					(size 1.27 1.27)
				)
			)
		)
		(property "MPN" "KMR211NGLFS"
			(at 317.5 86.36 0)
			(effects
				(font
					(size 1.27 1.27)
					(thickness 0.15)
				)
			)
		)
		(property "Manufacturer" "C&K"
			(at 337.82 106.68 0)
			(effects
				(font
					(size 1.27 1.27)
					(thickness 0.15)
				)
				(justify left bottom)
				(hide yes)
			)
		)
		(property "Author" "Antmicro"
			(at 337.82 109.22 0)
			(effects
				(font
					(size 1.27 1.27)
					(thickness 0.15)
				)
				(justify left bottom)
				(hide yes)
			)
		)
		(property "License" "Apache-2.0"
			(at 337.82 111.76 0)
			(effects
				(font
					(size 1.27 1.27)
					(thickness 0.15)
				)
				(justify left bottom)
				(hide yes)
			)
		)
		(pin "1"
		)
		(pin "2"
		)
		(pin "3"
		)
		(pin "4"
		)
		(instances
			(project "k410t-devboard"
				(path ""
					(reference "S2")
					(unit 1)
				)
			)
		)
	)
	(symbol
		(lib_id "antmicropower:GND")
		(at 186.69 213.36 0)
		(unit 1)
		(exclude_from_sim no)
		(in_bom yes)
		(on_board yes)
		(dnp no)
		(property "Reference" "#PWR0176"
			(at 186.69 219.71 0)
			(effects
				(font
					(size 1.27 1.27)
				)
				(hide yes)
			)
		)
		(property "Value" "GND"
			(at 186.69 217.17 0)
			(effects
				(font
					(size 1.27 1.27)
				)
			)
		)
		(property "Footprint" ""
			(at 195.58 220.98 0)
			(effects
				(font
					(size 1.27 1.27)
					(thickness 0.15)
				)
				(justify left bottom)
				(hide yes)
			)
		)
		(property "Datasheet" ""
			(at 195.58 226.06 0)
			(effects
				(font
					(size 1.27 1.27)
					(thickness 0.15)
				)
				(justify left bottom)
				(hide yes)
			)
		)
		(property "Description" ""
			(at 186.69 213.36 0)
			(effects
				(font
					(size 1.27 1.27)
				)
			)
		)
		(property "Author" "Antmicro"
			(at 195.58 220.98 0)
			(effects
				(font
					(size 1.27 1.27)
					(thickness 0.15)
				)
				(justify left bottom)
				(hide yes)
			)
		)
		(property "License" "Apache-2.0"
			(at 195.58 223.52 0)
			(effects
				(font
					(size 1.27 1.27)
					(thickness 0.15)
				)
				(justify left bottom)
				(hide yes)
			)
		)
		(pin "1"
		)
		(instances
			(project "k410t-devboard"
				(path ""
					(reference "#PWR0176")
					(unit 1)
				)
			)
		)
	)
	(symbol
		(lib_id "antmicroResistors0402:R_100R_0402")
		(at 279.4 48.26 180)
		(unit 1)
		(exclude_from_sim no)
		(in_bom yes)
		(on_board yes)
		(dnp no)
		(property "Reference" "R139"
			(at 281.94 46.99 0)
			(effects
				(font
					(size 1.27 1.27)
				)
			)
		)
		(property "Value" "R_100R_0402"
			(at 259.08 35.56 0)
			(effects
				(font
					(size 1.27 1.27)
					(thickness 0.15)
				)
				(justify left bottom)
				(hide yes)
			)
		)
		(property "Footprint" "antmicro-footprints:R_0402_1005Metric"
			(at 259.08 33.02 0)
			(effects
				(font
					(size 1.27 1.27)
					(thickness 0.15)
				)
				(justify left bottom)
				(hide yes)
			)
		)
		(property "Datasheet" "https://www.bourns.com/docs/product-datasheets/cr.pdf"
			(at 259.08 30.48 0)
			(effects
				(font
					(size 1.27 1.27)
					(thickness 0.15)
				)
				(justify left bottom)
				(hide yes)
			)
		)
		(property "Description" ""
			(at 279.4 48.26 0)
			(effects
				(font
					(size 1.27 1.27)
				)
			)
		)
		(property "Manufacturer" "Bourns"
			(at 259.08 25.4 0)
			(effects
				(font
					(size 1.27 1.27)
					(thickness 0.15)
				)
				(justify left bottom)
				(hide yes)
			)
		)
		(property "MPN" "CR0402-FX-1000GLF"
			(at 259.08 27.94 0)
			(effects
				(font
					(size 1.27 1.27)
					(thickness 0.15)
				)
				(justify left bottom)
				(hide yes)
			)
		)
		(property "Val" "100R"
			(at 271.78 46.99 0)
			(effects
				(font
					(size 1.27 1.27)
					(thickness 0.15)
				)
			)
		)
		(property "License" "Apache-2.0"
			(at 259.08 22.86 0)
			(effects
				(font
					(size 1.27 1.27)
					(thickness 0.15)
				)
				(justify left bottom)
				(hide yes)
			)
		)
		(property "Author" "Antmicro"
			(at 259.08 20.32 0)
			(effects
				(font
					(size 1.27 1.27)
					(thickness 0.15)
				)
				(justify left bottom)
				(hide yes)
			)
		)
		(property "Tolerance" "1%"
			(at 259.08 38.1 0)
			(effects
				(font
					(size 1.27 1.27)
				)
				(justify left bottom)
				(hide yes)
			)
		)
		(pin "1"
		)
		(pin "2"
		)
		(instances
			(project "k410t-devboard"
				(path ""
					(reference "R139")
					(unit 1)
				)
			)
		)
	)
	(symbol
		(lib_id "antmicropower:GND")
		(at 138.43 261.62 0)
		(unit 1)
		(exclude_from_sim no)
		(in_bom yes)
		(on_board yes)
		(dnp no)
		(property "Reference" "#PWR0166"
			(at 138.43 267.97 0)
			(effects
				(font
					(size 1.27 1.27)
				)
				(hide yes)
			)
		)
		(property "Value" "GND"
			(at 138.43 265.43 0)
			(effects
				(font
					(size 1.27 1.27)
				)
			)
		)
		(property "Footprint" ""
			(at 147.32 269.24 0)
			(effects
				(font
					(size 1.27 1.27)
					(thickness 0.15)
				)
				(justify left bottom)
				(hide yes)
			)
		)
		(property "Datasheet" ""
			(at 147.32 274.32 0)
			(effects
				(font
					(size 1.27 1.27)
					(thickness 0.15)
				)
				(justify left bottom)
				(hide yes)
			)
		)
		(property "Description" ""
			(at 138.43 261.62 0)
			(effects
				(font
					(size 1.27 1.27)
				)
			)
		)
		(property "Author" "Antmicro"
			(at 147.32 269.24 0)
			(effects
				(font
					(size 1.27 1.27)
					(thickness 0.15)
				)
				(justify left bottom)
				(hide yes)
			)
		)
		(property "License" "Apache-2.0"
			(at 147.32 271.78 0)
			(effects
				(font
					(size 1.27 1.27)
					(thickness 0.15)
				)
				(justify left bottom)
				(hide yes)
			)
		)
		(pin "1"
		)
		(instances
			(project "k410t-devboard"
				(path ""
					(reference "#PWR0166")
					(unit 1)
				)
			)
		)
	)
	(symbol
		(lib_id "antmicroResistorNetworksArrays:4x10k_0201_array")
		(at 234.95 275.59 180)
		(unit 1)
		(exclude_from_sim no)
		(in_bom yes)
		(on_board yes)
		(dnp no)
		(property "Reference" "R133"
			(at 217.17 269.875 0)
			(effects
				(font
					(size 1.27 1.27)
				)
			)
		)
		(property "Value" "4x10k_0201_array"
			(at 208.28 267.97 0)
			(effects
				(font
					(size 1.27 1.27)
					(thickness 0.15)
				)
				(justify left bottom)
				(hide yes)
			)
		)
		(property "Footprint" "antmicro-footprints:R_Array_4x0201_Panasonic_EXB18V"
			(at 208.28 262.89 0)
			(effects
				(font
					(size 1.27 1.27)
					(thickness 0.15)
				)
				(justify left bottom)
				(hide yes)
			)
		)
		(property "Datasheet" "http://industrial.panasonic.com/cdbs/www-data/pdf/AOC0000/AOC0000C14.pdf"
			(at 208.28 260.35 0)
			(effects
				(font
					(size 1.27 1.27)
					(thickness 0.15)
				)
				(justify left bottom)
				(hide yes)
			)
		)
		(property "Description" ""
			(at 234.95 275.59 0)
			(effects
				(font
					(size 1.27 1.27)
				)
			)
		)
		(property "MPN" "EXB-18V103JX"
			(at 208.28 257.81 0)
			(effects
				(font
					(size 1.27 1.27)
					(thickness 0.15)
				)
				(justify left bottom)
				(hide yes)
			)
		)
		(property "Manufacturer" "Panasonic"
			(at 208.28 255.27 0)
			(effects
				(font
					(size 1.27 1.27)
					(thickness 0.15)
				)
				(justify left bottom)
				(hide yes)
			)
		)
		(property "Val" "4x10k_0201"
			(at 217.17 272.415 0)
			(effects
				(font
					(size 1.27 1.27)
					(thickness 0.15)
				)
			)
		)
		(property "Author" "Antmicro"
			(at 208.28 252.73 0)
			(effects
				(font
					(size 1.27 1.27)
					(thickness 0.15)
				)
				(justify left bottom)
				(hide yes)
			)
		)
		(property "License" "Apache-2.0"
			(at 208.28 250.19 0)
			(effects
				(font
					(size 1.27 1.27)
					(thickness 0.15)
				)
				(justify left bottom)
				(hide yes)
			)
		)
		(pin "1"
		)
		(pin "2"
		)
		(pin "3"
		)
		(pin "4"
		)
		(pin "5"
		)
		(pin "6"
		)
		(pin "7"
		)
		(pin "8"
		)
		(instances
			(project "k410t-devboard"
				(path ""
					(reference "R133")
					(unit 1)
				)
			)
		)
	)
	(symbol
		(lib_id "antmicroResistors0402:R_1k_0402")
		(at 54.61 173.99 0)
		(unit 1)
		(exclude_from_sim no)
		(in_bom yes)
		(on_board yes)
		(dnp no)
		(property "Reference" "R108"
			(at 57.15 168.91 0)
			(effects
				(font
					(size 1.27 1.27)
				)
			)
		)
		(property "Value" "R_1k_0402"
			(at 74.93 186.69 0)
			(effects
				(font
					(size 1.27 1.27)
					(thickness 0.15)
				)
				(justify left bottom)
				(hide yes)
			)
		)
		(property "Footprint" "antmicro-footprints:R_0402_1005Metric"
			(at 74.93 189.23 0)
			(effects
				(font
					(size 1.27 1.27)
					(thickness 0.15)
				)
				(justify left bottom)
				(hide yes)
			)
		)
		(property "Datasheet" "https://www.bourns.com/docs/product-datasheets/cr.pdf"
			(at 74.93 191.77 0)
			(effects
				(font
					(size 1.27 1.27)
					(thickness 0.15)
				)
				(justify left bottom)
				(hide yes)
			)
		)
		(property "Description" ""
			(at 54.61 173.99 0)
			(effects
				(font
					(size 1.27 1.27)
				)
			)
		)
		(property "Manufacturer" "Bourns"
			(at 74.93 196.85 0)
			(effects
				(font
					(size 1.27 1.27)
					(thickness 0.15)
				)
				(justify left bottom)
				(hide yes)
			)
		)
		(property "MPN" "CR0402-FX-1001GLF"
			(at 74.93 194.31 0)
			(effects
				(font
					(size 1.27 1.27)
					(thickness 0.15)
				)
				(justify left bottom)
				(hide yes)
			)
		)
		(property "Val" "1k"
			(at 57.15 171.45 0)
			(effects
				(font
					(size 1.27 1.27)
					(thickness 0.15)
				)
			)
		)
		(property "License" "Apache-2.0"
			(at 74.93 199.39 0)
			(effects
				(font
					(size 1.27 1.27)
					(thickness 0.15)
				)
				(justify left bottom)
				(hide yes)
			)
		)
		(property "Author" "Antmicro"
			(at 74.93 201.93 0)
			(effects
				(font
					(size 1.27 1.27)
					(thickness 0.15)
				)
				(justify left bottom)
				(hide yes)
			)
		)
		(property "Tolerance" "1%"
			(at 74.93 184.15 0)
			(effects
				(font
					(size 1.27 1.27)
				)
				(justify left bottom)
				(hide yes)
			)
		)
		(pin "1"
		)
		(pin "2"
		)
		(instances
			(project "k410t-devboard"
				(path ""
					(reference "R108")
					(unit 1)
				)
			)
		)
	)
	(symbol
		(lib_id "antmicropower:VCC_USR_A")
		(at 234.95 180.34 0)
		(mirror y)
		(unit 1)
		(exclude_from_sim no)
		(in_bom yes)
		(on_board yes)
		(dnp no)
		(fields_autoplaced yes)
		(property "Reference" "#PWR0445"
			(at 234.95 184.15 0)
			(effects
				(font
					(size 1.27 1.27)
				)
				(hide yes)
			)
		)
		(property "Value" "VCC_USR_A"
			(at 234.95 176.53 0)
			(effects
				(font
					(size 1.27 1.27)
				)
			)
		)
		(property "Footprint" ""
			(at 234.95 180.34 0)
			(effects
				(font
					(size 1.27 1.27)
				)
				(hide yes)
			)
		)
		(property "Datasheet" ""
			(at 234.95 180.34 0)
			(effects
				(font
					(size 1.27 1.27)
				)
				(hide yes)
			)
		)
		(property "Description" ""
			(at 234.95 180.34 0)
			(effects
				(font
					(size 1.27 1.27)
				)
			)
		)
		(pin "1"
		)
		(instances
			(project "k410t-devboard"
				(path ""
					(reference "#PWR0445")
					(unit 1)
				)
			)
		)
	)
	(symbol
		(lib_id "antmicroTVSDiodes:ESDA25P35-1U1M")
		(at 279.4 114.3 90)
		(mirror x)
		(unit 1)
		(exclude_from_sim no)
		(in_bom yes)
		(on_board yes)
		(dnp no)
		(property "Reference" "D34"
			(at 276.86 118.4275 90)
			(effects
				(font
					(size 1.27 1.27)
				)
				(justify left)
			)
		)
		(property "Value" "ESDA25P35-1U1M"
			(at 276.86 115.8876 90)
			(effects
				(font
					(size 1.27 1.27)
					(thickness 0.15)
				)
				(justify left)
				(hide yes)
			)
		)
		(property "Footprint" "antmicro-footprints:QFN-2L_1.6x1x0.55mm"
			(at 289.56 138.43 0)
			(effects
				(font
					(size 1.27 1.27)
					(thickness 0.15)
				)
				(justify left bottom)
				(hide yes)
			)
		)
		(property "Datasheet" "https://www.st.com/resource/en/datasheet/esda25p35-1u1m.pdf"
			(at 292.1 138.43 0)
			(effects
				(font
					(size 1.27 1.27)
					(thickness 0.15)
				)
				(justify left bottom)
				(hide yes)
			)
		)
		(property "Description" ""
			(at 279.4 114.3 0)
			(effects
				(font
					(size 1.27 1.27)
				)
			)
		)
		(property "MPN" "ESDA25P35-1U1M"
			(at 276.86 115.8875 90)
			(effects
				(font
					(size 1.27 1.27)
					(thickness 0.15)
				)
				(justify left)
			)
		)
		(property "Manufacturer" "STMicroelectronics"
			(at 297.18 138.43 0)
			(effects
				(font
					(size 1.27 1.27)
					(thickness 0.15)
				)
				(justify left bottom)
				(hide yes)
			)
		)
		(property "Author" "Antmicro"
			(at 299.72 138.43 0)
			(effects
				(font
					(size 1.27 1.27)
					(thickness 0.15)
				)
				(justify left bottom)
				(hide yes)
			)
		)
		(property "License" "Apache-2.0"
			(at 302.26 138.43 0)
			(effects
				(font
					(size 1.27 1.27)
					(thickness 0.15)
				)
				(justify left bottom)
				(hide yes)
			)
		)
		(property "Public" "False"
			(at 297.18 134.62 0)
			(effects
				(font
					(size 1.27 1.27)
				)
				(justify left bottom)
				(hide yes)
			)
		)
		(pin "1"
		)
		(pin "2"
		)
		(instances
			(project "k410t-devboard"
				(path ""
					(reference "D34")
					(unit 1)
				)
			)
		)
	)
	(symbol
		(lib_id "antmicropower:GND")
		(at 179.07 261.62 0)
		(unit 1)
		(exclude_from_sim no)
		(in_bom yes)
		(on_board yes)
		(dnp no)
		(property "Reference" "#PWR0169"
			(at 179.07 267.97 0)
			(effects
				(font
					(size 1.27 1.27)
				)
				(hide yes)
			)
		)
		(property "Value" "GND"
			(at 179.07 265.43 0)
			(effects
				(font
					(size 1.27 1.27)
				)
			)
		)
		(property "Footprint" ""
			(at 187.96 269.24 0)
			(effects
				(font
					(size 1.27 1.27)
					(thickness 0.15)
				)
				(justify left bottom)
				(hide yes)
			)
		)
		(property "Datasheet" ""
			(at 187.96 274.32 0)
			(effects
				(font
					(size 1.27 1.27)
					(thickness 0.15)
				)
				(justify left bottom)
				(hide yes)
			)
		)
		(property "Description" ""
			(at 179.07 261.62 0)
			(effects
				(font
					(size 1.27 1.27)
				)
			)
		)
		(property "Author" "Antmicro"
			(at 187.96 269.24 0)
			(effects
				(font
					(size 1.27 1.27)
					(thickness 0.15)
				)
				(justify left bottom)
				(hide yes)
			)
		)
		(property "License" "Apache-2.0"
			(at 187.96 271.78 0)
			(effects
				(font
					(size 1.27 1.27)
					(thickness 0.15)
				)
				(justify left bottom)
				(hide yes)
			)
		)
		(pin "1"
		)
		(instances
			(project "k410t-devboard"
				(path ""
					(reference "#PWR0169")
					(unit 1)
				)
			)
		)
	)
	(symbol
		(lib_id "antmicroLEDIndicationDiscrete:LED_B_0603_KP-1608QBC-D")
		(at 158.75 212.09 0)
		(mirror y)
		(unit 1)
		(exclude_from_sim no)
		(in_bom yes)
		(on_board yes)
		(dnp no)
		(property "Reference" "D25"
			(at 154.94 204.47 0)
			(effects
				(font
					(size 1.27 1.27)
				)
			)
		)
		(property "Value" "LED_B_0603_KP-1608QBC-D"
			(at 154.94 215.265 0)
			(effects
				(font
					(size 1.27 1.27)
					(thickness 0.15)
				)
				(hide yes)
			)
		)
		(property "Footprint" "antmicro-footprints:LED_0603_1608Metric_B"
			(at 135.89 222.25 0)
			(effects
				(font
					(size 1.27 1.27)
					(thickness 0.15)
				)
				(justify left bottom)
				(hide yes)
			)
		)
		(property "Datasheet" "https://www.kingbright.com/attachments/file/psearch/000/00/00/KP-1608QBC-D(Ver.24B).pdf"
			(at 135.89 224.79 0)
			(effects
				(font
					(size 1.27 1.27)
					(thickness 0.15)
				)
				(justify left bottom)
				(hide yes)
			)
		)
		(property "Description" ""
			(at 158.75 212.09 0)
			(effects
				(font
					(size 1.27 1.27)
				)
			)
		)
		(property "MPN" "KP-1608QBC-D"
			(at 135.89 227.33 0)
			(effects
				(font
					(size 1.27 1.27)
					(thickness 0.15)
				)
				(justify left bottom)
				(hide yes)
			)
		)
		(property "Manufacturer" "Kingbright"
			(at 135.89 229.87 0)
			(effects
				(font
					(size 1.27 1.27)
					(thickness 0.15)
				)
				(justify left bottom)
				(hide yes)
			)
		)
		(property "Color" "Blue"
			(at 154.94 207.01 0)
			(effects
				(font
					(size 1.27 1.27)
					(thickness 0.15)
				)
			)
		)
		(property "Author" "Antmicro"
			(at 135.89 234.95 0)
			(effects
				(font
					(size 1.27 1.27)
					(thickness 0.15)
				)
				(justify left bottom)
				(hide yes)
			)
		)
		(property "License" "Apache-2.0"
			(at 135.89 237.49 0)
			(effects
				(font
					(size 1.27 1.27)
					(thickness 0.15)
				)
				(justify left bottom)
				(hide yes)
			)
		)
		(property "Public" "False"
			(at 138.43 229.87 0)
			(effects
				(font
					(size 1.27 1.27)
				)
				(justify left bottom)
				(hide yes)
			)
		)
		(pin "1"
		)
		(pin "2"
		)
		(instances
			(project "k410t-devboard"
				(path ""
					(reference "D25")
					(unit 1)
				)
			)
		)
	)
	(symbol
		(lib_id "antmicropower:GND")
		(at 381 115.57 0)
		(unit 1)
		(exclude_from_sim no)
		(in_bom yes)
		(on_board yes)
		(dnp no)
		(property "Reference" "#PWR0195"
			(at 381 121.92 0)
			(effects
				(font
					(size 1.27 1.27)
				)
				(hide yes)
			)
		)
		(property "Value" "GND"
			(at 381 119.38 0)
			(effects
				(font
					(size 1.27 1.27)
				)
			)
		)
		(property "Footprint" ""
			(at 389.89 123.19 0)
			(effects
				(font
					(size 1.27 1.27)
					(thickness 0.15)
				)
				(justify left bottom)
				(hide yes)
			)
		)
		(property "Datasheet" ""
			(at 389.89 128.27 0)
			(effects
				(font
					(size 1.27 1.27)
					(thickness 0.15)
				)
				(justify left bottom)
				(hide yes)
			)
		)
		(property "Description" ""
			(at 381 115.57 0)
			(effects
				(font
					(size 1.27 1.27)
				)
			)
		)
		(property "Author" "Antmicro"
			(at 389.89 123.19 0)
			(effects
				(font
					(size 1.27 1.27)
					(thickness 0.15)
				)
				(justify left bottom)
				(hide yes)
			)
		)
		(property "License" "Apache-2.0"
			(at 389.89 125.73 0)
			(effects
				(font
					(size 1.27 1.27)
					(thickness 0.15)
				)
				(justify left bottom)
				(hide yes)
			)
		)
		(pin "1"
		)
		(instances
			(project "k410t-devboard"
				(path ""
					(reference "#PWR0195")
					(unit 1)
				)
			)
		)
	)
	(symbol
		(lib_id "antmicroCapacitors0402:C_1u_0402")
		(at 86.36 250.19 90)
		(unit 1)
		(exclude_from_sim no)
		(in_bom no)
		(on_board yes)
		(dnp yes)
		(property "Reference" "C213"
			(at 86.995 245.745 90)
			(effects
				(font
					(size 1.27 1.27)
				)
				(justify right)
			)
		)
		(property "Value" "C_1u_0402"
			(at 96.52 229.87 0)
			(effects
				(font
					(size 1.27 1.27)
					(thickness 0.15)
				)
				(justify left bottom)
				(hide yes)
			)
		)
		(property "Footprint" "antmicro-footprints:C_0402_1005Metric"
			(at 99.06 229.87 0)
			(effects
				(font
					(size 1.27 1.27)
					(thickness 0.15)
				)
				(justify left bottom)
				(hide yes)
			)
		)
		(property "Datasheet" "https://product.tdk.com/en/search/capacitor/ceramic/mlcc/info?part_no=C1005X6S1A105K050BC"
			(at 101.6 229.87 0)
			(effects
				(font
					(size 1.27 1.27)
					(thickness 0.15)
				)
				(justify left bottom)
				(hide yes)
			)
		)
		(property "Description" ""
			(at 86.36 250.19 0)
			(effects
				(font
					(size 1.27 1.27)
				)
			)
		)
		(property "Manufacturer" "TDK"
			(at 106.68 229.87 0)
			(effects
				(font
					(size 1.27 1.27)
					(thickness 0.15)
				)
				(justify left bottom)
				(hide yes)
			)
		)
		(property "MPN" "C1005X6S1A105K050BC"
			(at 104.14 229.87 0)
			(effects
				(font
					(size 1.27 1.27)
					(thickness 0.15)
				)
				(justify left bottom)
				(hide yes)
			)
		)
		(property "Val" "1u"
			(at 86.995 249.555 90)
			(effects
				(font
					(size 1.27 1.27)
					(thickness 0.15)
				)
				(justify right)
			)
		)
		(property "DNP" "DNP"
			(at 88.265 247.65 90)
			(effects
				(font
					(size 1.27 1.27)
				)
				(justify right)
			)
		)
		(property "License" "Apache-2.0"
			(at 109.22 229.87 0)
			(effects
				(font
					(size 1.27 1.27)
					(thickness 0.15)
				)
				(justify left bottom)
				(hide yes)
			)
		)
		(property "Author" "Antmicro"
			(at 111.76 229.87 0)
			(effects
				(font
					(size 1.27 1.27)
					(thickness 0.15)
				)
				(justify left bottom)
				(hide yes)
			)
		)
		(property "Voltage" ""
			(at 114.3 229.87 0)
			(effects
				(font
					(size 1.27 1.27)
				)
				(justify left bottom)
				(hide yes)
			)
		)
		(property "Dielectric" ""
			(at 116.84 229.87 0)
			(effects
				(font
					(size 1.27 1.27)
				)
				(justify left bottom)
				(hide yes)
			)
		)
		(pin "1"
		)
		(pin "2"
		)
		(instances
			(project "k410t-devboard"
				(path ""
					(reference "C213")
					(unit 1)
				)
			)
		)
	)
	(symbol
		(lib_id "antmicropower:GND")
		(at 111.76 62.23 0)
		(unit 1)
		(exclude_from_sim no)
		(in_bom yes)
		(on_board yes)
		(dnp no)
		(property "Reference" "#PWR0147"
			(at 111.76 68.58 0)
			(effects
				(font
					(size 1.27 1.27)
				)
				(hide yes)
			)
		)
		(property "Value" "GND"
			(at 111.76 66.04 0)
			(effects
				(font
					(size 1.27 1.27)
				)
			)
		)
		(property "Footprint" ""
			(at 120.65 69.85 0)
			(effects
				(font
					(size 1.27 1.27)
					(thickness 0.15)
				)
				(justify left bottom)
				(hide yes)
			)
		)
		(property "Datasheet" ""
			(at 120.65 74.93 0)
			(effects
				(font
					(size 1.27 1.27)
					(thickness 0.15)
				)
				(justify left bottom)
				(hide yes)
			)
		)
		(property "Description" ""
			(at 111.76 62.23 0)
			(effects
				(font
					(size 1.27 1.27)
				)
			)
		)
		(property "Author" "Antmicro"
			(at 120.65 69.85 0)
			(effects
				(font
					(size 1.27 1.27)
					(thickness 0.15)
				)
				(justify left bottom)
				(hide yes)
			)
		)
		(property "License" "Apache-2.0"
			(at 120.65 72.39 0)
			(effects
				(font
					(size 1.27 1.27)
					(thickness 0.15)
				)
				(justify left bottom)
				(hide yes)
			)
		)
		(pin "1"
		)
		(instances
			(project "k410t-devboard"
				(path ""
					(reference "#PWR0147")
					(unit 1)
				)
			)
		)
	)
	(symbol
		(lib_id "antmicroResistors0402:R_100k_0402")
		(at 190.5 219.71 0)
		(unit 1)
		(exclude_from_sim no)
		(in_bom yes)
		(on_board yes)
		(dnp no)
		(property "Reference" "R360"
			(at 193.04 214.63 0)
			(effects
				(font
					(size 1.27 1.27)
				)
			)
		)
		(property "Value" "R_100k_0402"
			(at 210.82 232.41 0)
			(effects
				(font
					(size 1.27 1.27)
					(thickness 0.15)
				)
				(justify left bottom)
				(hide yes)
			)
		)
		(property "Footprint" "antmicro-footprints:R_0402_1005Metric"
			(at 210.82 234.95 0)
			(effects
				(font
					(size 1.27 1.27)
					(thickness 0.15)
				)
				(justify left bottom)
				(hide yes)
			)
		)
		(property "Datasheet" "https://www.bourns.com/docs/product-datasheets/cr.pdf"
			(at 210.82 237.49 0)
			(effects
				(font
					(size 1.27 1.27)
					(thickness 0.15)
				)
				(justify left bottom)
				(hide yes)
			)
		)
		(property "Description" ""
			(at 190.5 219.71 0)
			(effects
				(font
					(size 1.27 1.27)
				)
			)
		)
		(property "Manufacturer" "Bourns"
			(at 210.82 242.57 0)
			(effects
				(font
					(size 1.27 1.27)
					(thickness 0.15)
				)
				(justify left bottom)
				(hide yes)
			)
		)
		(property "MPN" "CR0402-FX-1003GLF"
			(at 210.82 240.03 0)
			(effects
				(font
					(size 1.27 1.27)
					(thickness 0.15)
				)
				(justify left bottom)
				(hide yes)
			)
		)
		(property "Val" "100k"
			(at 193.04 217.17 0)
			(effects
				(font
					(size 1.27 1.27)
					(thickness 0.15)
				)
			)
		)
		(property "License" "Apache-2.0"
			(at 210.82 245.11 0)
			(effects
				(font
					(size 1.27 1.27)
					(thickness 0.15)
				)
				(justify left bottom)
				(hide yes)
			)
		)
		(property "Author" "Antmicro"
			(at 210.82 247.65 0)
			(effects
				(font
					(size 1.27 1.27)
					(thickness 0.15)
				)
				(justify left bottom)
				(hide yes)
			)
		)
		(property "Tolerance" "1%"
			(at 210.82 229.87 0)
			(effects
				(font
					(size 1.27 1.27)
				)
				(justify left bottom)
				(hide yes)
			)
		)
		(pin "1"
		)
		(pin "2"
		)
		(instances
			(project "k410t-devboard"
				(path ""
					(reference "R360")
					(unit 1)
				)
			)
		)
	)
	(symbol
		(lib_id "antmicropower:+3.3V")
		(at 326.39 31.75 0)
		(unit 1)
		(exclude_from_sim no)
		(in_bom yes)
		(on_board yes)
		(dnp no)
		(fields_autoplaced yes)
		(property "Reference" "#PWR0173"
			(at 326.39 35.56 0)
			(effects
				(font
					(size 1.27 1.27)
				)
				(hide yes)
			)
		)
		(property "Value" "+3V3"
			(at 326.39 28.194 0)
			(effects
				(font
					(size 1.27 1.27)
				)
			)
		)
		(property "Footprint" ""
			(at 326.39 31.75 0)
			(effects
				(font
					(size 1.27 1.27)
				)
				(hide yes)
			)
		)
		(property "Datasheet" ""
			(at 326.39 31.75 0)
			(effects
				(font
					(size 1.27 1.27)
				)
				(hide yes)
			)
		)
		(property "Description" ""
			(at 326.39 31.75 0)
			(effects
				(font
					(size 1.27 1.27)
				)
			)
		)
		(pin "1"
		)
		(instances
			(project "k410t-devboard"
				(path ""
					(reference "#PWR0173")
					(unit 1)
				)
			)
		)
	)
	(symbol
		(lib_id "antmicroWire2BoardConnectors:JST_SH_1x4_BM04B-SRSS-TB-LF-SN")
		(at 180.34 250.19 0)
		(unit 1)
		(exclude_from_sim no)
		(in_bom yes)
		(on_board yes)
		(dnp no)
		(property "Reference" "J8"
			(at 177.8 245.11 0)
			(effects
				(font
					(size 1.27 1.27)
					(thickness 0.15)
				)
				(justify left)
			)
		)
		(property "Value" "JST_SH_1x4_BM04B-SRSS-TB-LF-SN"
			(at 200.66 257.81 0)
			(effects
				(font
					(size 1.27 1.27)
					(thickness 0.15)
				)
				(justify left bottom)
				(hide yes)
			)
		)
		(property "Footprint" "antmicro-footprints:Conn_JST_SH_1x4_BM04B-SRSS-TB-LF-SN"
			(at 200.66 260.35 0)
			(effects
				(font
					(size 1.27 1.27)
					(thickness 0.15)
				)
				(justify left bottom)
				(hide yes)
			)
		)
		(property "Datasheet" "https://www.jst-mfg.com/product/pdf/eng/eSH.pdf"
			(at 200.66 262.89 0)
			(effects
				(font
					(size 1.27 1.27)
					(thickness 0.15)
				)
				(justify left bottom)
				(hide yes)
			)
		)
		(property "Description" ""
			(at 180.34 250.19 0)
			(effects
				(font
					(size 1.27 1.27)
				)
			)
		)
		(property "MPN" "BM04B-SRSS-TB(LF)(SN) "
			(at 177.8 247.65 0)
			(effects
				(font
					(size 1.27 1.27)
					(thickness 0.15)
				)
				(justify left)
			)
		)
		(property "Manufacturer" "JST Automotive Connectors"
			(at 200.66 267.97 0)
			(effects
				(font
					(size 1.27 1.27)
					(thickness 0.15)
				)
				(justify left bottom)
				(hide yes)
			)
		)
		(property "Author" "Antmicro"
			(at 200.66 270.51 0)
			(effects
				(font
					(size 1.27 1.27)
					(thickness 0.15)
				)
				(justify left bottom)
				(hide yes)
			)
		)
		(property "License" "Apache-2.0"
			(at 200.66 273.05 0)
			(effects
				(font
					(size 1.27 1.27)
					(thickness 0.15)
				)
				(justify left bottom)
				(hide yes)
			)
		)
		(pin "1"
		)
		(pin "2"
		)
		(pin "3"
		)
		(pin "4"
		)
		(pin "MP"
		)
		(instances
			(project "k410t-devboard"
				(path ""
					(reference "J8")
					(unit 1)
				)
			)
		)
	)
	(symbol
		(lib_id "antmicroTVSDiodes:TPD4E05U06QDQARQ1")
		(at 246.38 229.87 0)
		(mirror y)
		(unit 1)
		(exclude_from_sim no)
		(in_bom yes)
		(on_board yes)
		(dnp no)
		(fields_autoplaced yes)
		(property "Reference" "U45"
			(at 240.665 222.25 0)
			(effects
				(font
					(size 1.27 1.27)
				)
			)
		)
		(property "Value" "TPD4E05U06QDQARQ1"
			(at 240.665 242.57 0)
			(effects
				(font
					(size 1.27 1.27)
					(thickness 0.15)
				)
				(hide yes)
			)
		)
		(property "Footprint" "antmicro-footprints:USON-10_2.5x1mm_P0.5mm"
			(at 222.25 234.95 0)
			(effects
				(font
					(size 1.27 1.27)
					(thickness 0.15)
				)
				(justify left bottom)
				(hide yes)
			)
		)
		(property "Datasheet" "https://www.ti.com/lit/ds/symlink/tpd4e05u06-q1.pdf?HQS=dis-mous-null-mousermode-dsf-pf-null-wwe&ts=1663591265741&ref_url=https%253A%252F%252Fwww.mouser.com%252F"
			(at 222.25 237.49 0)
			(effects
				(font
					(size 1.27 1.27)
					(thickness 0.15)
				)
				(justify left bottom)
				(hide yes)
			)
		)
		(property "Description" ""
			(at 246.38 229.87 0)
			(effects
				(font
					(size 1.27 1.27)
				)
			)
		)
		(property "Manufacturer" "Texas Instruments"
			(at 222.25 240.03 0)
			(effects
				(font
					(size 1.27 1.27)
					(thickness 0.15)
				)
				(justify left bottom)
				(hide yes)
			)
		)
		(property "MPN" "TPD4E05U06QDQARQ1"
			(at 240.665 224.79 0)
			(effects
				(font
					(size 1.27 1.27)
					(thickness 0.15)
				)
			)
		)
		(property "Author" "Antmicro"
			(at 222.25 245.11 0)
			(effects
				(font
					(size 1.27 1.27)
					(thickness 0.15)
				)
				(justify left bottom)
				(hide yes)
			)
		)
		(property "License" "Apache-2.0"
			(at 222.25 247.65 0)
			(effects
				(font
					(size 1.27 1.27)
					(thickness 0.15)
				)
				(justify left bottom)
				(hide yes)
			)
		)
		(pin "1"
		)
		(pin "10"
		)
		(pin "2"
		)
		(pin "3"
		)
		(pin "4"
		)
		(pin "5"
		)
		(pin "6"
		)
		(pin "7"
		)
		(pin "8"
		)
		(pin "9"
		)
		(instances
			(project "k410t-devboard"
				(path ""
					(reference "U45")
					(unit 1)
				)
			)
		)
	)
	(symbol
		(lib_id "antmicropower:+5V")
		(at 170.18 242.57 0)
		(unit 1)
		(exclude_from_sim no)
		(in_bom yes)
		(on_board yes)
		(dnp no)
		(property "Reference" "#PWR0156"
			(at 170.18 246.38 0)
			(effects
				(font
					(size 1.27 1.27)
				)
				(hide yes)
			)
		)
		(property "Value" "+5V"
			(at 169.545 238.76 0)
			(effects
				(font
					(size 1.27 1.27)
				)
			)
		)
		(property "Footprint" ""
			(at 170.18 242.57 0)
			(effects
				(font
					(size 1.27 1.27)
				)
				(hide yes)
			)
		)
		(property "Datasheet" ""
			(at 170.18 242.57 0)
			(effects
				(font
					(size 1.27 1.27)
				)
				(hide yes)
			)
		)
		(property "Description" ""
			(at 170.18 242.57 0)
			(effects
				(font
					(size 1.27 1.27)
				)
			)
		)
		(property "Author" "Antmicro"
			(at 185.42 250.19 0)
			(effects
				(font
					(size 1.27 1.27)
					(thickness 0.15)
				)
				(justify left bottom)
				(hide yes)
			)
		)
		(property "License" "Apache-2.0"
			(at 185.42 252.73 0)
			(effects
				(font
					(size 1.27 1.27)
					(thickness 0.15)
				)
				(justify left bottom)
				(hide yes)
			)
		)
		(pin "1"
		)
		(instances
			(project "k410t-devboard"
				(path ""
					(reference "#PWR0156")
					(unit 1)
				)
			)
		)
	)
	(symbol
		(lib_id "antmicroResistors0402:R_100R_0402")
		(at 87.63 90.17 180)
		(unit 1)
		(exclude_from_sim no)
		(in_bom yes)
		(on_board yes)
		(dnp no)
		(property "Reference" "R117"
			(at 90.17 88.9 0)
			(effects
				(font
					(size 1.27 1.27)
				)
			)
		)
		(property "Value" "R_100R_0402"
			(at 67.31 77.47 0)
			(effects
				(font
					(size 1.27 1.27)
					(thickness 0.15)
				)
				(justify left bottom)
				(hide yes)
			)
		)
		(property "Footprint" "antmicro-footprints:R_0402_1005Metric"
			(at 67.31 74.93 0)
			(effects
				(font
					(size 1.27 1.27)
					(thickness 0.15)
				)
				(justify left bottom)
				(hide yes)
			)
		)
		(property "Datasheet" "https://www.bourns.com/docs/product-datasheets/cr.pdf"
			(at 67.31 72.39 0)
			(effects
				(font
					(size 1.27 1.27)
					(thickness 0.15)
				)
				(justify left bottom)
				(hide yes)
			)
		)
		(property "Description" ""
			(at 87.63 90.17 0)
			(effects
				(font
					(size 1.27 1.27)
				)
			)
		)
		(property "Manufacturer" "Bourns"
			(at 67.31 67.31 0)
			(effects
				(font
					(size 1.27 1.27)
					(thickness 0.15)
				)
				(justify left bottom)
				(hide yes)
			)
		)
		(property "MPN" "CR0402-FX-1000GLF"
			(at 67.31 69.85 0)
			(effects
				(font
					(size 1.27 1.27)
					(thickness 0.15)
				)
				(justify left bottom)
				(hide yes)
			)
		)
		(property "Val" "100R"
			(at 80.01 88.9 0)
			(effects
				(font
					(size 1.27 1.27)
					(thickness 0.15)
				)
			)
		)
		(property "License" "Apache-2.0"
			(at 67.31 64.77 0)
			(effects
				(font
					(size 1.27 1.27)
					(thickness 0.15)
				)
				(justify left bottom)
				(hide yes)
			)
		)
		(property "Author" "Antmicro"
			(at 67.31 62.23 0)
			(effects
				(font
					(size 1.27 1.27)
					(thickness 0.15)
				)
				(justify left bottom)
				(hide yes)
			)
		)
		(property "Tolerance" "1%"
			(at 67.31 80.01 0)
			(effects
				(font
					(size 1.27 1.27)
				)
				(justify left bottom)
				(hide yes)
			)
		)
		(pin "1"
		)
		(pin "2"
		)
		(instances
			(project "k410t-devboard"
				(path ""
					(reference "R117")
					(unit 1)
				)
			)
		)
	)
	(symbol
		(lib_id "antmicroTransistorsFETsMOSFETsSingle:BSS138PW")
		(at 96.52 162.56 90)
		(unit 1)
		(exclude_from_sim no)
		(in_bom yes)
		(on_board yes)
		(dnp no)
		(fields_autoplaced yes)
		(property "Reference" "Q8"
			(at 93.98 146.05 90)
			(effects
				(font
					(size 1.27 1.27)
				)
			)
		)
		(property "Value" "BSS138PW"
			(at 93.98 148.59 90)
			(effects
				(font
					(size 1.27 1.27)
					(thickness 0.15)
				)
			)
		)
		(property "Footprint" "antmicro-footprints:SC70-3"
			(at 107.95 139.7 0)
			(effects
				(font
					(size 1.27 1.27)
					(thickness 0.15)
				)
				(justify left bottom)
				(hide yes)
			)
		)
		(property "Datasheet" "https://assets.nexperia.com/documents/data-sheet/BSS138PW.pdf"
			(at 110.49 139.7 0)
			(effects
				(font
					(size 1.27 1.27)
					(thickness 0.15)
				)
				(justify left bottom)
				(hide yes)
			)
		)
		(property "Description" ""
			(at 96.52 162.56 0)
			(effects
				(font
					(size 1.27 1.27)
				)
			)
		)
		(property "MPN" "BSS138PW"
			(at 113.03 139.7 0)
			(effects
				(font
					(size 1.27 1.27)
					(thickness 0.15)
				)
				(justify left bottom)
				(hide yes)
			)
		)
		(property "Manufacturer" "Nexperia"
			(at 115.57 139.7 0)
			(effects
				(font
					(size 1.27 1.27)
					(thickness 0.15)
				)
				(justify left bottom)
				(hide yes)
			)
		)
		(property "Author" "Antmicro"
			(at 118.11 139.7 0)
			(effects
				(font
					(size 1.27 1.27)
					(thickness 0.15)
				)
				(justify left bottom)
				(hide yes)
			)
		)
		(property "License" "Apache-2.0"
			(at 120.65 139.7 0)
			(effects
				(font
					(size 1.27 1.27)
					(thickness 0.15)
				)
				(justify left bottom)
				(hide yes)
			)
		)
		(pin "1"
		)
		(pin "2"
		)
		(pin "3"
		)
		(instances
			(project "k410t-devboard"
				(path ""
					(reference "Q8")
					(unit 1)
				)
			)
		)
	)
	(symbol
		(lib_id "antmicropower:+3.3V")
		(at 49.53 151.13 0)
		(unit 1)
		(exclude_from_sim no)
		(in_bom yes)
		(on_board yes)
		(dnp no)
		(fields_autoplaced yes)
		(property "Reference" "#PWR0128"
			(at 49.53 154.94 0)
			(effects
				(font
					(size 1.27 1.27)
				)
				(hide yes)
			)
		)
		(property "Value" "+3V3"
			(at 49.53 147.574 0)
			(effects
				(font
					(size 1.27 1.27)
				)
			)
		)
		(property "Footprint" ""
			(at 49.53 151.13 0)
			(effects
				(font
					(size 1.27 1.27)
				)
				(hide yes)
			)
		)
		(property "Datasheet" ""
			(at 49.53 151.13 0)
			(effects
				(font
					(size 1.27 1.27)
				)
				(hide yes)
			)
		)
		(property "Description" ""
			(at 49.53 151.13 0)
			(effects
				(font
					(size 1.27 1.27)
				)
			)
		)
		(pin "1"
		)
		(instances
			(project "k410t-devboard"
				(path ""
					(reference "#PWR0128")
					(unit 1)
				)
			)
		)
	)
	(symbol
		(lib_id "antmicropower:+1V8")
		(at 302.26 81.28 0)
		(unit 1)
		(exclude_from_sim no)
		(in_bom yes)
		(on_board yes)
		(dnp no)
		(fields_autoplaced yes)
		(property "Reference" "#PWR0164"
			(at 302.26 85.09 0)
			(effects
				(font
					(size 1.27 1.27)
				)
				(hide yes)
			)
		)
		(property "Value" "+1V8"
			(at 302.26 77.724 0)
			(effects
				(font
					(size 1.27 1.27)
				)
			)
		)
		(property "Footprint" ""
			(at 317.5 88.9 0)
			(effects
				(font
					(size 1.27 1.27)
					(thickness 0.15)
				)
				(justify left bottom)
				(hide yes)
			)
		)
		(property "Datasheet" ""
			(at 317.5 91.44 0)
			(effects
				(font
					(size 1.27 1.27)
					(thickness 0.15)
				)
				(justify left bottom)
				(hide yes)
			)
		)
		(property "Description" ""
			(at 302.26 81.28 0)
			(effects
				(font
					(size 1.27 1.27)
				)
			)
		)
		(property "Author" "Antmicro"
			(at 317.5 88.9 0)
			(effects
				(font
					(size 1.27 1.27)
					(thickness 0.15)
				)
				(justify left bottom)
				(hide yes)
			)
		)
		(property "License" "Apache-2.0"
			(at 317.5 91.44 0)
			(effects
				(font
					(size 1.27 1.27)
					(thickness 0.15)
				)
				(justify left bottom)
				(hide yes)
			)
		)
		(pin "1"
		)
		(instances
			(project "k410t-devboard"
				(path ""
					(reference "#PWR0164")
					(unit 1)
				)
			)
		)
	)
	(symbol
		(lib_id "antmicroResistors0402:R_100R_0402")
		(at 279.4 43.18 180)
		(unit 1)
		(exclude_from_sim no)
		(in_bom yes)
		(on_board yes)
		(dnp no)
		(property "Reference" "R137"
			(at 281.94 41.91 0)
			(effects
				(font
					(size 1.27 1.27)
				)
			)
		)
		(property "Value" "R_100R_0402"
			(at 259.08 30.48 0)
			(effects
				(font
					(size 1.27 1.27)
					(thickness 0.15)
				)
				(justify left bottom)
				(hide yes)
			)
		)
		(property "Footprint" "antmicro-footprints:R_0402_1005Metric"
			(at 259.08 27.94 0)
			(effects
				(font
					(size 1.27 1.27)
					(thickness 0.15)
				)
				(justify left bottom)
				(hide yes)
			)
		)
		(property "Datasheet" "https://www.bourns.com/docs/product-datasheets/cr.pdf"
			(at 259.08 25.4 0)
			(effects
				(font
					(size 1.27 1.27)
					(thickness 0.15)
				)
				(justify left bottom)
				(hide yes)
			)
		)
		(property "Description" ""
			(at 279.4 43.18 0)
			(effects
				(font
					(size 1.27 1.27)
				)
			)
		)
		(property "Manufacturer" "Bourns"
			(at 259.08 20.32 0)
			(effects
				(font
					(size 1.27 1.27)
					(thickness 0.15)
				)
				(justify left bottom)
				(hide yes)
			)
		)
		(property "MPN" "CR0402-FX-1000GLF"
			(at 259.08 22.86 0)
			(effects
				(font
					(size 1.27 1.27)
					(thickness 0.15)
				)
				(justify left bottom)
				(hide yes)
			)
		)
		(property "Val" "100R"
			(at 271.78 41.91 0)
			(effects
				(font
					(size 1.27 1.27)
					(thickness 0.15)
				)
			)
		)
		(property "License" "Apache-2.0"
			(at 259.08 17.78 0)
			(effects
				(font
					(size 1.27 1.27)
					(thickness 0.15)
				)
				(justify left bottom)
				(hide yes)
			)
		)
		(property "Author" "Antmicro"
			(at 259.08 15.24 0)
			(effects
				(font
					(size 1.27 1.27)
					(thickness 0.15)
				)
				(justify left bottom)
				(hide yes)
			)
		)
		(property "Tolerance" "1%"
			(at 259.08 33.02 0)
			(effects
				(font
					(size 1.27 1.27)
				)
				(justify left bottom)
				(hide yes)
			)
		)
		(pin "1"
		)
		(pin "2"
		)
		(instances
			(project "k410t-devboard"
				(path ""
					(reference "R137")
					(unit 1)
				)
			)
		)
	)
	(symbol
		(lib_id "antmicropower:GND")
		(at 104.14 213.36 0)
		(unit 1)
		(exclude_from_sim no)
		(in_bom yes)
		(on_board yes)
		(dnp no)
		(property "Reference" "#PWR0146"
			(at 104.14 219.71 0)
			(effects
				(font
					(size 1.27 1.27)
				)
				(hide yes)
			)
		)
		(property "Value" "GND"
			(at 104.14 217.17 0)
			(effects
				(font
					(size 1.27 1.27)
				)
			)
		)
		(property "Footprint" ""
			(at 113.03 220.98 0)
			(effects
				(font
					(size 1.27 1.27)
					(thickness 0.15)
				)
				(justify left bottom)
				(hide yes)
			)
		)
		(property "Datasheet" ""
			(at 113.03 226.06 0)
			(effects
				(font
					(size 1.27 1.27)
					(thickness 0.15)
				)
				(justify left bottom)
				(hide yes)
			)
		)
		(property "Description" ""
			(at 104.14 213.36 0)
			(effects
				(font
					(size 1.27 1.27)
				)
			)
		)
		(property "Author" "Antmicro"
			(at 113.03 220.98 0)
			(effects
				(font
					(size 1.27 1.27)
					(thickness 0.15)
				)
				(justify left bottom)
				(hide yes)
			)
		)
		(property "License" "Apache-2.0"
			(at 113.03 223.52 0)
			(effects
				(font
					(size 1.27 1.27)
					(thickness 0.15)
				)
				(justify left bottom)
				(hide yes)
			)
		)
		(pin "1"
		)
		(instances
			(project "k410t-devboard"
				(path ""
					(reference "#PWR0146")
					(unit 1)
				)
			)
		)
	)
	(symbol
		(lib_id "antmicropower:GND")
		(at 377.19 99.695 0)
		(unit 1)
		(exclude_from_sim no)
		(in_bom yes)
		(on_board yes)
		(dnp no)
		(property "Reference" "#PWR0802"
			(at 377.19 106.045 0)
			(effects
				(font
					(size 1.27 1.27)
				)
				(hide yes)
			)
		)
		(property "Value" "GND"
			(at 377.19 103.505 0)
			(effects
				(font
					(size 1.27 1.27)
				)
			)
		)
		(property "Footprint" ""
			(at 386.08 107.315 0)
			(effects
				(font
					(size 1.27 1.27)
					(thickness 0.15)
				)
				(justify left bottom)
				(hide yes)
			)
		)
		(property "Datasheet" ""
			(at 386.08 112.395 0)
			(effects
				(font
					(size 1.27 1.27)
					(thickness 0.15)
				)
				(justify left bottom)
				(hide yes)
			)
		)
		(property "Description" ""
			(at 377.19 99.695 0)
			(effects
				(font
					(size 1.27 1.27)
				)
			)
		)
		(property "Author" "Antmicro"
			(at 386.08 107.315 0)
			(effects
				(font
					(size 1.27 1.27)
					(thickness 0.15)
				)
				(justify left bottom)
				(hide yes)
			)
		)
		(property "License" "Apache-2.0"
			(at 386.08 109.855 0)
			(effects
				(font
					(size 1.27 1.27)
					(thickness 0.15)
				)
				(justify left bottom)
				(hide yes)
			)
		)
		(pin "1"
		)
		(instances
			(project "k410t-devboard"
				(path ""
					(reference "#PWR0802")
					(unit 1)
				)
			)
		)
	)
	(symbol
		(lib_id "antmicropower:VCC_USR_B")
		(at 323.85 172.72 0)
		(mirror y)
		(unit 1)
		(exclude_from_sim no)
		(in_bom yes)
		(on_board yes)
		(dnp no)
		(fields_autoplaced yes)
		(property "Reference" "#PWR0444"
			(at 323.85 176.53 0)
			(effects
				(font
					(size 1.27 1.27)
				)
				(hide yes)
			)
		)
		(property "Value" "VCC_USR_B"
			(at 323.85 168.91 0)
			(effects
				(font
					(size 1.27 1.27)
				)
			)
		)
		(property "Footprint" ""
			(at 323.85 172.72 0)
			(effects
				(font
					(size 1.27 1.27)
				)
				(hide yes)
			)
		)
		(property "Datasheet" ""
			(at 323.85 172.72 0)
			(effects
				(font
					(size 1.27 1.27)
				)
				(hide yes)
			)
		)
		(property "Description" ""
			(at 323.85 172.72 0)
			(effects
				(font
					(size 1.27 1.27)
				)
			)
		)
		(pin "1"
		)
		(instances
			(project "k410t-devboard"
				(path ""
					(reference "#PWR0444")
					(unit 1)
				)
			)
		)
	)
	(symbol
		(lib_id "antmicropower:+5V")
		(at 129.54 242.57 0)
		(unit 1)
		(exclude_from_sim no)
		(in_bom yes)
		(on_board yes)
		(dnp no)
		(property "Reference" "#PWR0149"
			(at 129.54 246.38 0)
			(effects
				(font
					(size 1.27 1.27)
				)
				(hide yes)
			)
		)
		(property "Value" "+5V"
			(at 128.905 238.76 0)
			(effects
				(font
					(size 1.27 1.27)
				)
			)
		)
		(property "Footprint" ""
			(at 129.54 242.57 0)
			(effects
				(font
					(size 1.27 1.27)
				)
				(hide yes)
			)
		)
		(property "Datasheet" ""
			(at 129.54 242.57 0)
			(effects
				(font
					(size 1.27 1.27)
				)
				(hide yes)
			)
		)
		(property "Description" ""
			(at 129.54 242.57 0)
			(effects
				(font
					(size 1.27 1.27)
				)
			)
		)
		(property "Author" "Antmicro"
			(at 144.78 250.19 0)
			(effects
				(font
					(size 1.27 1.27)
					(thickness 0.15)
				)
				(justify left bottom)
				(hide yes)
			)
		)
		(property "License" "Apache-2.0"
			(at 144.78 252.73 0)
			(effects
				(font
					(size 1.27 1.27)
					(thickness 0.15)
				)
				(justify left bottom)
				(hide yes)
			)
		)
		(pin "1"
		)
		(instances
			(project "k410t-devboard"
				(path ""
					(reference "#PWR0149")
					(unit 1)
				)
			)
		)
	)
	(symbol
		(lib_id "antmicroCapacitors0402:C_1u_0402")
		(at 129.54 250.19 90)
		(unit 1)
		(exclude_from_sim no)
		(in_bom yes)
		(on_board yes)
		(dnp no)
		(property "Reference" "C216"
			(at 130.175 245.745 90)
			(effects
				(font
					(size 1.27 1.27)
				)
				(justify right)
			)
		)
		(property "Value" "C_1u_0402"
			(at 139.7 229.87 0)
			(effects
				(font
					(size 1.27 1.27)
					(thickness 0.15)
				)
				(justify left bottom)
				(hide yes)
			)
		)
		(property "Footprint" "antmicro-footprints:C_0402_1005Metric"
			(at 142.24 229.87 0)
			(effects
				(font
					(size 1.27 1.27)
					(thickness 0.15)
				)
				(justify left bottom)
				(hide yes)
			)
		)
		(property "Datasheet" "https://product.tdk.com/en/search/capacitor/ceramic/mlcc/info?part_no=C1005X6S1A105K050BC"
			(at 144.78 229.87 0)
			(effects
				(font
					(size 1.27 1.27)
					(thickness 0.15)
				)
				(justify left bottom)
				(hide yes)
			)
		)
		(property "Description" ""
			(at 129.54 250.19 0)
			(effects
				(font
					(size 1.27 1.27)
				)
			)
		)
		(property "Manufacturer" "TDK"
			(at 149.86 229.87 0)
			(effects
				(font
					(size 1.27 1.27)
					(thickness 0.15)
				)
				(justify left bottom)
				(hide yes)
			)
		)
		(property "MPN" "C1005X6S1A105K050BC"
			(at 147.32 229.87 0)
			(effects
				(font
					(size 1.27 1.27)
					(thickness 0.15)
				)
				(justify left bottom)
				(hide yes)
			)
		)
		(property "Val" "1u"
			(at 130.175 249.555 90)
			(effects
				(font
					(size 1.27 1.27)
					(thickness 0.15)
				)
				(justify right)
			)
		)
		(property "License" "Apache-2.0"
			(at 152.4 229.87 0)
			(effects
				(font
					(size 1.27 1.27)
					(thickness 0.15)
				)
				(justify left bottom)
				(hide yes)
			)
		)
		(property "Author" "Antmicro"
			(at 154.94 229.87 0)
			(effects
				(font
					(size 1.27 1.27)
					(thickness 0.15)
				)
				(justify left bottom)
				(hide yes)
			)
		)
		(property "Voltage" ""
			(at 157.48 229.87 0)
			(effects
				(font
					(size 1.27 1.27)
				)
				(justify left bottom)
				(hide yes)
			)
		)
		(property "Dielectric" ""
			(at 160.02 229.87 0)
			(effects
				(font
					(size 1.27 1.27)
				)
				(justify left bottom)
				(hide yes)
			)
		)
		(pin "1"
		)
		(pin "2"
		)
		(instances
			(project "k410t-devboard"
				(path ""
					(reference "C216")
					(unit 1)
				)
			)
		)
	)
	(symbol
		(lib_id "antmicroResistors0402:R_100R_0402")
		(at 140.97 30.48 180)
		(unit 1)
		(exclude_from_sim no)
		(in_bom yes)
		(on_board yes)
		(dnp no)
		(property "Reference" "R120"
			(at 143.51 29.21 0)
			(effects
				(font
					(size 1.27 1.27)
				)
			)
		)
		(property "Value" "R_100R_0402"
			(at 120.65 17.78 0)
			(effects
				(font
					(size 1.27 1.27)
					(thickness 0.15)
				)
				(justify left bottom)
				(hide yes)
			)
		)
		(property "Footprint" "antmicro-footprints:R_0402_1005Metric"
			(at 120.65 15.24 0)
			(effects
				(font
					(size 1.27 1.27)
					(thickness 0.15)
				)
				(justify left bottom)
				(hide yes)
			)
		)
		(property "Datasheet" "https://www.bourns.com/docs/product-datasheets/cr.pdf"
			(at 120.65 12.7 0)
			(effects
				(font
					(size 1.27 1.27)
					(thickness 0.15)
				)
				(justify left bottom)
				(hide yes)
			)
		)
		(property "Description" ""
			(at 140.97 30.48 0)
			(effects
				(font
					(size 1.27 1.27)
				)
			)
		)
		(property "Manufacturer" "Bourns"
			(at 120.65 7.62 0)
			(effects
				(font
					(size 1.27 1.27)
					(thickness 0.15)
				)
				(justify left bottom)
				(hide yes)
			)
		)
		(property "MPN" "CR0402-FX-1000GLF"
			(at 120.65 10.16 0)
			(effects
				(font
					(size 1.27 1.27)
					(thickness 0.15)
				)
				(justify left bottom)
				(hide yes)
			)
		)
		(property "Val" "100R"
			(at 133.35 29.21 0)
			(effects
				(font
					(size 1.27 1.27)
					(thickness 0.15)
				)
			)
		)
		(property "License" "Apache-2.0"
			(at 120.65 5.08 0)
			(effects
				(font
					(size 1.27 1.27)
					(thickness 0.15)
				)
				(justify left bottom)
				(hide yes)
			)
		)
		(property "Author" "Antmicro"
			(at 120.65 2.54 0)
			(effects
				(font
					(size 1.27 1.27)
					(thickness 0.15)
				)
				(justify left bottom)
				(hide yes)
			)
		)
		(property "Tolerance" "1%"
			(at 120.65 20.32 0)
			(effects
				(font
					(size 1.27 1.27)
				)
				(justify left bottom)
				(hide yes)
			)
		)
		(pin "1"
		)
		(pin "2"
		)
		(instances
			(project "k410t-devboard"
				(path ""
					(reference "R120")
					(unit 1)
				)
			)
		)
	)
	(symbol
		(lib_id "antmicroTransistorsFETsMOSFETsSingle:BSS138PW")
		(at 179.07 219.71 90)
		(unit 1)
		(exclude_from_sim no)
		(in_bom yes)
		(on_board yes)
		(dnp no)
		(fields_autoplaced yes)
		(property "Reference" "Q16"
			(at 176.53 205.105 90)
			(effects
				(font
					(size 1.27 1.27)
				)
			)
		)
		(property "Value" "BSS138PW"
			(at 176.53 207.645 90)
			(effects
				(font
					(size 1.27 1.27)
					(thickness 0.15)
				)
			)
		)
		(property "Footprint" "antmicro-footprints:SC70-3"
			(at 190.5 196.85 0)
			(effects
				(font
					(size 1.27 1.27)
					(thickness 0.15)
				)
				(justify left bottom)
				(hide yes)
			)
		)
		(property "Datasheet" "https://assets.nexperia.com/documents/data-sheet/BSS138PW.pdf"
			(at 193.04 196.85 0)
			(effects
				(font
					(size 1.27 1.27)
					(thickness 0.15)
				)
				(justify left bottom)
				(hide yes)
			)
		)
		(property "Description" ""
			(at 179.07 219.71 0)
			(effects
				(font
					(size 1.27 1.27)
				)
			)
		)
		(property "MPN" "BSS138PW"
			(at 195.58 196.85 0)
			(effects
				(font
					(size 1.27 1.27)
					(thickness 0.15)
				)
				(justify left bottom)
				(hide yes)
			)
		)
		(property "Manufacturer" "Nexperia"
			(at 198.12 196.85 0)
			(effects
				(font
					(size 1.27 1.27)
					(thickness 0.15)
				)
				(justify left bottom)
				(hide yes)
			)
		)
		(property "Author" "Antmicro"
			(at 200.66 196.85 0)
			(effects
				(font
					(size 1.27 1.27)
					(thickness 0.15)
				)
				(justify left bottom)
				(hide yes)
			)
		)
		(property "License" "Apache-2.0"
			(at 203.2 196.85 0)
			(effects
				(font
					(size 1.27 1.27)
					(thickness 0.15)
				)
				(justify left bottom)
				(hide yes)
			)
		)
		(pin "1"
		)
		(pin "2"
		)
		(pin "3"
		)
		(instances
			(project "k410t-devboard"
				(path ""
					(reference "Q16")
					(unit 1)
				)
			)
		)
	)
	(symbol
		(lib_id "antmicropower:GND")
		(at 318.77 54.61 0)
		(unit 1)
		(exclude_from_sim no)
		(in_bom yes)
		(on_board yes)
		(dnp no)
		(property "Reference" "#PWR0190"
			(at 318.77 60.96 0)
			(effects
				(font
					(size 1.27 1.27)
				)
				(hide yes)
			)
		)
		(property "Value" "GND"
			(at 318.77 58.42 0)
			(effects
				(font
					(size 1.27 1.27)
				)
			)
		)
		(property "Footprint" ""
			(at 327.66 62.23 0)
			(effects
				(font
					(size 1.27 1.27)
					(thickness 0.15)
				)
				(justify left bottom)
				(hide yes)
			)
		)
		(property "Datasheet" ""
			(at 327.66 67.31 0)
			(effects
				(font
					(size 1.27 1.27)
					(thickness 0.15)
				)
				(justify left bottom)
				(hide yes)
			)
		)
		(property "Description" ""
			(at 318.77 54.61 0)
			(effects
				(font
					(size 1.27 1.27)
				)
			)
		)
		(property "Author" "Antmicro"
			(at 327.66 62.23 0)
			(effects
				(font
					(size 1.27 1.27)
					(thickness 0.15)
				)
				(justify left bottom)
				(hide yes)
			)
		)
		(property "License" "Apache-2.0"
			(at 327.66 64.77 0)
			(effects
				(font
					(size 1.27 1.27)
					(thickness 0.15)
				)
				(justify left bottom)
				(hide yes)
			)
		)
		(pin "1"
		)
		(instances
			(project "k410t-devboard"
				(path ""
					(reference "#PWR0190")
					(unit 1)
				)
			)
		)
	)
	(symbol
		(lib_id "antmicropower:+3.3V")
		(at 68.58 261.62 0)
		(unit 1)
		(exclude_from_sim no)
		(in_bom yes)
		(on_board yes)
		(dnp no)
		(property "Reference" "#PWR0132"
			(at 68.58 265.43 0)
			(effects
				(font
					(size 1.27 1.27)
				)
				(hide yes)
			)
		)
		(property "Value" "+3V3"
			(at 68.58 257.81 0)
			(effects
				(font
					(size 1.27 1.27)
				)
			)
		)
		(property "Footprint" ""
			(at 68.58 261.62 0)
			(effects
				(font
					(size 1.27 1.27)
				)
				(hide yes)
			)
		)
		(property "Datasheet" ""
			(at 68.58 261.62 0)
			(effects
				(font
					(size 1.27 1.27)
				)
				(hide yes)
			)
		)
		(property "Description" ""
			(at 68.58 261.62 0)
			(effects
				(font
					(size 1.27 1.27)
				)
			)
		)
		(pin "1"
		)
		(instances
			(project "k410t-devboard"
				(path ""
					(reference "#PWR0132")
					(unit 1)
				)
			)
		)
	)
	(symbol
		(lib_id "antmicroResistors0402:R_100R_0402")
		(at 140.97 35.56 180)
		(unit 1)
		(exclude_from_sim no)
		(in_bom yes)
		(on_board yes)
		(dnp no)
		(property "Reference" "R122"
			(at 143.51 34.29 0)
			(effects
				(font
					(size 1.27 1.27)
				)
			)
		)
		(property "Value" "R_100R_0402"
			(at 120.65 22.86 0)
			(effects
				(font
					(size 1.27 1.27)
					(thickness 0.15)
				)
				(justify left bottom)
				(hide yes)
			)
		)
		(property "Footprint" "antmicro-footprints:R_0402_1005Metric"
			(at 120.65 20.32 0)
			(effects
				(font
					(size 1.27 1.27)
					(thickness 0.15)
				)
				(justify left bottom)
				(hide yes)
			)
		)
		(property "Datasheet" "https://www.bourns.com/docs/product-datasheets/cr.pdf"
			(at 120.65 17.78 0)
			(effects
				(font
					(size 1.27 1.27)
					(thickness 0.15)
				)
				(justify left bottom)
				(hide yes)
			)
		)
		(property "Description" ""
			(at 140.97 35.56 0)
			(effects
				(font
					(size 1.27 1.27)
				)
			)
		)
		(property "Manufacturer" "Bourns"
			(at 120.65 12.7 0)
			(effects
				(font
					(size 1.27 1.27)
					(thickness 0.15)
				)
				(justify left bottom)
				(hide yes)
			)
		)
		(property "MPN" "CR0402-FX-1000GLF"
			(at 120.65 15.24 0)
			(effects
				(font
					(size 1.27 1.27)
					(thickness 0.15)
				)
				(justify left bottom)
				(hide yes)
			)
		)
		(property "Val" "100R"
			(at 133.35 34.29 0)
			(effects
				(font
					(size 1.27 1.27)
					(thickness 0.15)
				)
			)
		)
		(property "License" "Apache-2.0"
			(at 120.65 10.16 0)
			(effects
				(font
					(size 1.27 1.27)
					(thickness 0.15)
				)
				(justify left bottom)
				(hide yes)
			)
		)
		(property "Author" "Antmicro"
			(at 120.65 7.62 0)
			(effects
				(font
					(size 1.27 1.27)
					(thickness 0.15)
				)
				(justify left bottom)
				(hide yes)
			)
		)
		(property "Tolerance" "1%"
			(at 120.65 25.4 0)
			(effects
				(font
					(size 1.27 1.27)
				)
				(justify left bottom)
				(hide yes)
			)
		)
		(pin "1"
		)
		(pin "2"
		)
		(instances
			(project "k410t-devboard"
				(path ""
					(reference "R122")
					(unit 1)
				)
			)
		)
	)
	(symbol
		(lib_id "antmicropower:GND")
		(at 276.86 212.09 0)
		(mirror y)
		(unit 1)
		(exclude_from_sim no)
		(in_bom yes)
		(on_board yes)
		(dnp no)
		(property "Reference" "#PWR0183"
			(at 276.86 218.44 0)
			(effects
				(font
					(size 1.27 1.27)
				)
				(hide yes)
			)
		)
		(property "Value" "GND"
			(at 276.86 215.9 0)
			(effects
				(font
					(size 1.27 1.27)
				)
			)
		)
		(property "Footprint" ""
			(at 267.97 219.71 0)
			(effects
				(font
					(size 1.27 1.27)
					(thickness 0.15)
				)
				(justify left bottom)
				(hide yes)
			)
		)
		(property "Datasheet" ""
			(at 267.97 224.79 0)
			(effects
				(font
					(size 1.27 1.27)
					(thickness 0.15)
				)
				(justify left bottom)
				(hide yes)
			)
		)
		(property "Description" ""
			(at 276.86 212.09 0)
			(effects
				(font
					(size 1.27 1.27)
				)
			)
		)
		(property "Author" "Antmicro"
			(at 267.97 219.71 0)
			(effects
				(font
					(size 1.27 1.27)
					(thickness 0.15)
				)
				(justify left bottom)
				(hide yes)
			)
		)
		(property "License" "Apache-2.0"
			(at 267.97 222.25 0)
			(effects
				(font
					(size 1.27 1.27)
					(thickness 0.15)
				)
				(justify left bottom)
				(hide yes)
			)
		)
		(pin "1"
		)
		(instances
			(project "k410t-devboard"
				(path ""
					(reference "#PWR0183")
					(unit 1)
				)
			)
		)
	)
	(symbol
		(lib_id "antmicroResistors0402:R_100k_0402")
		(at 190.5 182.88 0)
		(unit 1)
		(exclude_from_sim no)
		(in_bom yes)
		(on_board yes)
		(dnp no)
		(property "Reference" "R358"
			(at 193.04 177.8 0)
			(effects
				(font
					(size 1.27 1.27)
				)
			)
		)
		(property "Value" "R_100k_0402"
			(at 210.82 195.58 0)
			(effects
				(font
					(size 1.27 1.27)
					(thickness 0.15)
				)
				(justify left bottom)
				(hide yes)
			)
		)
		(property "Footprint" "antmicro-footprints:R_0402_1005Metric"
			(at 210.82 198.12 0)
			(effects
				(font
					(size 1.27 1.27)
					(thickness 0.15)
				)
				(justify left bottom)
				(hide yes)
			)
		)
		(property "Datasheet" "https://www.bourns.com/docs/product-datasheets/cr.pdf"
			(at 210.82 200.66 0)
			(effects
				(font
					(size 1.27 1.27)
					(thickness 0.15)
				)
				(justify left bottom)
				(hide yes)
			)
		)
		(property "Description" ""
			(at 190.5 182.88 0)
			(effects
				(font
					(size 1.27 1.27)
				)
			)
		)
		(property "Manufacturer" "Bourns"
			(at 210.82 205.74 0)
			(effects
				(font
					(size 1.27 1.27)
					(thickness 0.15)
				)
				(justify left bottom)
				(hide yes)
			)
		)
		(property "MPN" "CR0402-FX-1003GLF"
			(at 210.82 203.2 0)
			(effects
				(font
					(size 1.27 1.27)
					(thickness 0.15)
				)
				(justify left bottom)
				(hide yes)
			)
		)
		(property "Val" "100k"
			(at 193.04 180.34 0)
			(effects
				(font
					(size 1.27 1.27)
					(thickness 0.15)
				)
			)
		)
		(property "License" "Apache-2.0"
			(at 210.82 208.28 0)
			(effects
				(font
					(size 1.27 1.27)
					(thickness 0.15)
				)
				(justify left bottom)
				(hide yes)
			)
		)
		(property "Author" "Antmicro"
			(at 210.82 210.82 0)
			(effects
				(font
					(size 1.27 1.27)
					(thickness 0.15)
				)
				(justify left bottom)
				(hide yes)
			)
		)
		(property "Tolerance" "1%"
			(at 210.82 193.04 0)
			(effects
				(font
					(size 1.27 1.27)
				)
				(justify left bottom)
				(hide yes)
			)
		)
		(pin "1"
		)
		(pin "2"
		)
		(instances
			(project "k410t-devboard"
				(path ""
					(reference "R358")
					(unit 1)
				)
			)
		)
	)
	(symbol
		(lib_id "antmicropower:GND")
		(at 279.4 121.92 0)
		(unit 1)
		(exclude_from_sim no)
		(in_bom yes)
		(on_board yes)
		(dnp no)
		(property "Reference" "#PWR0184"
			(at 279.4 128.27 0)
			(effects
				(font
					(size 1.27 1.27)
				)
				(hide yes)
			)
		)
		(property "Value" "GND"
			(at 279.4 125.73 0)
			(effects
				(font
					(size 1.27 1.27)
				)
			)
		)
		(property "Footprint" ""
			(at 288.29 129.54 0)
			(effects
				(font
					(size 1.27 1.27)
					(thickness 0.15)
				)
				(justify left bottom)
				(hide yes)
			)
		)
		(property "Datasheet" ""
			(at 288.29 134.62 0)
			(effects
				(font
					(size 1.27 1.27)
					(thickness 0.15)
				)
				(justify left bottom)
				(hide yes)
			)
		)
		(property "Description" ""
			(at 279.4 121.92 0)
			(effects
				(font
					(size 1.27 1.27)
				)
			)
		)
		(property "Author" "Antmicro"
			(at 288.29 129.54 0)
			(effects
				(font
					(size 1.27 1.27)
					(thickness 0.15)
				)
				(justify left bottom)
				(hide yes)
			)
		)
		(property "License" "Apache-2.0"
			(at 288.29 132.08 0)
			(effects
				(font
					(size 1.27 1.27)
					(thickness 0.15)
				)
				(justify left bottom)
				(hide yes)
			)
		)
		(pin "1"
		)
		(instances
			(project "k410t-devboard"
				(path ""
					(reference "#PWR0184")
					(unit 1)
				)
			)
		)
	)
	(symbol
		(lib_id "antmicroPushbuttonSwitches:SW_KMR211NGLFS_SMD")
		(at 364.49 110.49 0)
		(unit 1)
		(exclude_from_sim no)
		(in_bom yes)
		(on_board yes)
		(dnp no)
		(property "Reference" "S5"
			(at 369.57 115.57 0)
			(effects
				(font
					(size 1.27 1.27)
				)
			)
		)
		(property "Value" "SW_KMR211NGLFS_SMD"
			(at 369.57 114.935 0)
			(effects
				(font
					(size 1.27 1.27)
					(thickness 0.15)
				)
				(hide yes)
			)
		)
		(property "Footprint" "antmicro-footprints:SW_KMR211NGLFS_SMD"
			(at 389.89 118.11 0)
			(effects
				(font
					(size 1.27 1.27)
					(thickness 0.15)
				)
				(justify left bottom)
				(hide yes)
			)
		)
		(property "Datasheet" "http://www.farnell.com/datasheets/2631211.pdf"
			(at 389.89 120.65 0)
			(effects
				(font
					(size 1.27 1.27)
					(thickness 0.15)
				)
				(justify left bottom)
				(hide yes)
			)
		)
		(property "Description" ""
			(at 364.49 110.49 0)
			(effects
				(font
					(size 1.27 1.27)
				)
			)
		)
		(property "MPN" "KMR211NGLFS"
			(at 369.57 118.11 0)
			(effects
				(font
					(size 1.27 1.27)
					(thickness 0.15)
				)
			)
		)
		(property "Manufacturer" "C&K"
			(at 389.89 125.73 0)
			(effects
				(font
					(size 1.27 1.27)
					(thickness 0.15)
				)
				(justify left bottom)
				(hide yes)
			)
		)
		(property "Author" "Antmicro"
			(at 389.89 128.27 0)
			(effects
				(font
					(size 1.27 1.27)
					(thickness 0.15)
				)
				(justify left bottom)
				(hide yes)
			)
		)
		(property "License" "Apache-2.0"
			(at 389.89 130.81 0)
			(effects
				(font
					(size 1.27 1.27)
					(thickness 0.15)
				)
				(justify left bottom)
				(hide yes)
			)
		)
		(pin "1"
		)
		(pin "2"
		)
		(pin "3"
		)
		(pin "4"
		)
		(instances
			(project "k410t-devboard"
				(path ""
					(reference "S5")
					(unit 1)
				)
			)
		)
	)
	(symbol
		(lib_id "antmicroResistors0402:R_100R_0402")
		(at 140.97 92.71 180)
		(unit 1)
		(exclude_from_sim no)
		(in_bom yes)
		(on_board yes)
		(dnp no)
		(property "Reference" "R126"
			(at 143.51 91.44 0)
			(effects
				(font
					(size 1.27 1.27)
				)
			)
		)
		(property "Value" "R_100R_0402"
			(at 120.65 80.01 0)
			(effects
				(font
					(size 1.27 1.27)
					(thickness 0.15)
				)
				(justify left bottom)
				(hide yes)
			)
		)
		(property "Footprint" "antmicro-footprints:R_0402_1005Metric"
			(at 120.65 77.47 0)
			(effects
				(font
					(size 1.27 1.27)
					(thickness 0.15)
				)
				(justify left bottom)
				(hide yes)
			)
		)
		(property "Datasheet" "https://www.bourns.com/docs/product-datasheets/cr.pdf"
			(at 120.65 74.93 0)
			(effects
				(font
					(size 1.27 1.27)
					(thickness 0.15)
				)
				(justify left bottom)
				(hide yes)
			)
		)
		(property "Description" ""
			(at 140.97 92.71 0)
			(effects
				(font
					(size 1.27 1.27)
				)
			)
		)
		(property "Manufacturer" "Bourns"
			(at 120.65 69.85 0)
			(effects
				(font
					(size 1.27 1.27)
					(thickness 0.15)
				)
				(justify left bottom)
				(hide yes)
			)
		)
		(property "MPN" "CR0402-FX-1000GLF"
			(at 120.65 72.39 0)
			(effects
				(font
					(size 1.27 1.27)
					(thickness 0.15)
				)
				(justify left bottom)
				(hide yes)
			)
		)
		(property "Val" "100R"
			(at 133.35 91.44 0)
			(effects
				(font
					(size 1.27 1.27)
					(thickness 0.15)
				)
			)
		)
		(property "License" "Apache-2.0"
			(at 120.65 67.31 0)
			(effects
				(font
					(size 1.27 1.27)
					(thickness 0.15)
				)
				(justify left bottom)
				(hide yes)
			)
		)
		(property "Author" "Antmicro"
			(at 120.65 64.77 0)
			(effects
				(font
					(size 1.27 1.27)
					(thickness 0.15)
				)
				(justify left bottom)
				(hide yes)
			)
		)
		(property "Tolerance" "1%"
			(at 120.65 82.55 0)
			(effects
				(font
					(size 1.27 1.27)
				)
				(justify left bottom)
				(hide yes)
			)
		)
		(pin "1"
		)
		(pin "2"
		)
		(instances
			(project "k410t-devboard"
				(path ""
					(reference "R126")
					(unit 1)
				)
			)
		)
	)
	(symbol
		(lib_id "antmicropower:GND")
		(at 365.76 201.93 0)
		(mirror y)
		(unit 1)
		(exclude_from_sim no)
		(in_bom yes)
		(on_board yes)
		(dnp no)
		(property "Reference" "#PWR0193"
			(at 365.76 208.28 0)
			(effects
				(font
					(size 1.27 1.27)
				)
				(hide yes)
			)
		)
		(property "Value" "GND"
			(at 365.76 205.74 0)
			(effects
				(font
					(size 1.27 1.27)
				)
			)
		)
		(property "Footprint" ""
			(at 356.87 209.55 0)
			(effects
				(font
					(size 1.27 1.27)
					(thickness 0.15)
				)
				(justify left bottom)
				(hide yes)
			)
		)
		(property "Datasheet" ""
			(at 356.87 214.63 0)
			(effects
				(font
					(size 1.27 1.27)
					(thickness 0.15)
				)
				(justify left bottom)
				(hide yes)
			)
		)
		(property "Description" ""
			(at 365.76 201.93 0)
			(effects
				(font
					(size 1.27 1.27)
				)
			)
		)
		(property "Author" "Antmicro"
			(at 356.87 209.55 0)
			(effects
				(font
					(size 1.27 1.27)
					(thickness 0.15)
				)
				(justify left bottom)
				(hide yes)
			)
		)
		(property "License" "Apache-2.0"
			(at 356.87 212.09 0)
			(effects
				(font
					(size 1.27 1.27)
					(thickness 0.15)
				)
				(justify left bottom)
				(hide yes)
			)
		)
		(pin "1"
		)
		(instances
			(project "k410t-devboard"
				(path ""
					(reference "#PWR0193")
					(unit 1)
				)
			)
		)
	)
	(symbol
		(lib_id "antmicroLEDIndicationDiscrete:LED_G_0603_KP-1608CGCK")
		(at 158.75 173.99 0)
		(mirror y)
		(unit 1)
		(exclude_from_sim no)
		(in_bom yes)
		(on_board yes)
		(dnp no)
		(property "Reference" "D23"
			(at 154.94 166.37 0)
			(effects
				(font
					(size 1.27 1.27)
				)
			)
		)
		(property "Value" "LED_G_0603_KP-1608CGCK"
			(at 154.94 177.165 0)
			(effects
				(font
					(size 1.27 1.27)
					(thickness 0.15)
				)
				(hide yes)
			)
		)
		(property "Footprint" "antmicro-footprints:LED_0603_1608Metric_G"
			(at 135.89 184.15 0)
			(effects
				(font
					(size 1.27 1.27)
					(thickness 0.15)
				)
				(justify left bottom)
				(hide yes)
			)
		)
		(property "Datasheet" "http://www.kingbright.com/attachments/file/psearch//000/00/00/KP-1608CGCK(Ver.23B).pdf"
			(at 135.89 186.69 0)
			(effects
				(font
					(size 1.27 1.27)
					(thickness 0.15)
				)
				(justify left bottom)
				(hide yes)
			)
		)
		(property "Description" ""
			(at 158.75 173.99 0)
			(effects
				(font
					(size 1.27 1.27)
				)
			)
		)
		(property "MPN" "KP-1608CGCK"
			(at 135.89 189.23 0)
			(effects
				(font
					(size 1.27 1.27)
					(thickness 0.15)
				)
				(justify left bottom)
				(hide yes)
			)
		)
		(property "Manufacturer" "Kingbright"
			(at 135.89 191.77 0)
			(effects
				(font
					(size 1.27 1.27)
					(thickness 0.15)
				)
				(justify left bottom)
				(hide yes)
			)
		)
		(property "Author" "Antmicro"
			(at 135.89 194.31 0)
			(effects
				(font
					(size 1.27 1.27)
					(thickness 0.15)
				)
				(justify left bottom)
				(hide yes)
			)
		)
		(property "License" "Apache-2.0"
			(at 135.89 196.85 0)
			(effects
				(font
					(size 1.27 1.27)
					(thickness 0.15)
				)
				(justify left bottom)
				(hide yes)
			)
		)
		(property "Color" "Green"
			(at 154.94 168.91 0)
			(effects
				(font
					(size 1.27 1.27)
				)
			)
		)
		(pin "1"
		)
		(pin "2"
		)
		(instances
			(project "k410t-devboard"
				(path ""
					(reference "D23")
					(unit 1)
				)
			)
		)
	)
	(symbol
		(lib_id "antmicropower:GND")
		(at 405.13 96.52 0)
		(unit 1)
		(exclude_from_sim no)
		(in_bom yes)
		(on_board yes)
		(dnp no)
		(property "Reference" "#PWR0196"
			(at 405.13 102.87 0)
			(effects
				(font
					(size 1.27 1.27)
				)
				(hide yes)
			)
		)
		(property "Value" "GND"
			(at 405.13 100.33 0)
			(effects
				(font
					(size 1.27 1.27)
				)
			)
		)
		(property "Footprint" ""
			(at 414.02 104.14 0)
			(effects
				(font
					(size 1.27 1.27)
					(thickness 0.15)
				)
				(justify left bottom)
				(hide yes)
			)
		)
		(property "Datasheet" ""
			(at 414.02 109.22 0)
			(effects
				(font
					(size 1.27 1.27)
					(thickness 0.15)
				)
				(justify left bottom)
				(hide yes)
			)
		)
		(property "Description" ""
			(at 405.13 96.52 0)
			(effects
				(font
					(size 1.27 1.27)
				)
			)
		)
		(property "Author" "Antmicro"
			(at 414.02 104.14 0)
			(effects
				(font
					(size 1.27 1.27)
					(thickness 0.15)
				)
				(justify left bottom)
				(hide yes)
			)
		)
		(property "License" "Apache-2.0"
			(at 414.02 106.68 0)
			(effects
				(font
					(size 1.27 1.27)
					(thickness 0.15)
				)
				(justify left bottom)
				(hide yes)
			)
		)
		(pin "1"
		)
		(instances
			(project "k410t-devboard"
				(path ""
					(reference "#PWR0196")
					(unit 1)
				)
			)
		)
	)
	(symbol
		(lib_id "antmicropower:+3.3V")
		(at 111.76 107.95 0)
		(unit 1)
		(exclude_from_sim no)
		(in_bom yes)
		(on_board yes)
		(dnp no)
		(fields_autoplaced yes)
		(property "Reference" "#PWR0144"
			(at 111.76 111.76 0)
			(effects
				(font
					(size 1.27 1.27)
				)
				(hide yes)
			)
		)
		(property "Value" "+3V3"
			(at 111.76 104.394 0)
			(effects
				(font
					(size 1.27 1.27)
				)
			)
		)
		(property "Footprint" ""
			(at 111.76 107.95 0)
			(effects
				(font
					(size 1.27 1.27)
				)
				(hide yes)
			)
		)
		(property "Datasheet" ""
			(at 111.76 107.95 0)
			(effects
				(font
					(size 1.27 1.27)
				)
				(hide yes)
			)
		)
		(property "Description" ""
			(at 111.76 107.95 0)
			(effects
				(font
					(size 1.27 1.27)
				)
			)
		)
		(pin "1"
		)
		(instances
			(project "k410t-devboard"
				(path ""
					(reference "#PWR0144")
					(unit 1)
				)
			)
		)
	)
	(symbol
		(lib_id "antmicroResistors0402:R_100k_0402")
		(at 76.2 250.19 90)
		(unit 1)
		(exclude_from_sim no)
		(in_bom yes)
		(on_board yes)
		(dnp no)
		(fields_autoplaced yes)
		(property "Reference" "R168"
			(at 78.105 246.3799 90)
			(effects
				(font
					(size 1.27 1.27)
				)
				(justify right)
			)
		)
		(property "Value" "R_100k_0402"
			(at 88.9 229.87 0)
			(effects
				(font
					(size 1.27 1.27)
					(thickness 0.15)
				)
				(justify left bottom)
				(hide yes)
			)
		)
		(property "Footprint" "antmicro-footprints:R_0402_1005Metric"
			(at 91.44 229.87 0)
			(effects
				(font
					(size 1.27 1.27)
					(thickness 0.15)
				)
				(justify left bottom)
				(hide yes)
			)
		)
		(property "Datasheet" "https://www.bourns.com/docs/product-datasheets/cr.pdf"
			(at 93.98 229.87 0)
			(effects
				(font
					(size 1.27 1.27)
					(thickness 0.15)
				)
				(justify left bottom)
				(hide yes)
			)
		)
		(property "Description" ""
			(at 76.2 250.19 0)
			(effects
				(font
					(size 1.27 1.27)
				)
			)
		)
		(property "Manufacturer" "Bourns"
			(at 99.06 229.87 0)
			(effects
				(font
					(size 1.27 1.27)
					(thickness 0.15)
				)
				(justify left bottom)
				(hide yes)
			)
		)
		(property "MPN" "CR0402-FX-1003GLF"
			(at 96.52 229.87 0)
			(effects
				(font
					(size 1.27 1.27)
					(thickness 0.15)
				)
				(justify left bottom)
				(hide yes)
			)
		)
		(property "Val" "100k"
			(at 78.105 248.9199 90)
			(effects
				(font
					(size 1.27 1.27)
					(thickness 0.15)
				)
				(justify right)
			)
		)
		(property "License" "Apache-2.0"
			(at 101.6 229.87 0)
			(effects
				(font
					(size 1.27 1.27)
					(thickness 0.15)
				)
				(justify left bottom)
				(hide yes)
			)
		)
		(property "Author" "Antmicro"
			(at 104.14 229.87 0)
			(effects
				(font
					(size 1.27 1.27)
					(thickness 0.15)
				)
				(justify left bottom)
				(hide yes)
			)
		)
		(property "Tolerance" "1%"
			(at 86.36 229.87 0)
			(effects
				(font
					(size 1.27 1.27)
				)
				(justify left bottom)
				(hide yes)
			)
		)
		(pin "1"
		)
		(pin "2"
		)
		(instances
			(project "k410t-devboard"
				(path ""
					(reference "R168")
					(unit 1)
				)
			)
		)
	)
	(symbol
		(lib_id "antmicroLEDIndicationDiscrete:LED_G_0603_KP-1608CGCK")
		(at 158.75 154.94 0)
		(mirror y)
		(unit 1)
		(exclude_from_sim no)
		(in_bom yes)
		(on_board yes)
		(dnp no)
		(property "Reference" "D22"
			(at 154.94 147.32 0)
			(effects
				(font
					(size 1.27 1.27)
				)
			)
		)
		(property "Value" "LED_G_0603_KP-1608CGCK"
			(at 154.94 158.115 0)
			(effects
				(font
					(size 1.27 1.27)
					(thickness 0.15)
				)
				(hide yes)
			)
		)
		(property "Footprint" "antmicro-footprints:LED_0603_1608Metric_G"
			(at 135.89 165.1 0)
			(effects
				(font
					(size 1.27 1.27)
					(thickness 0.15)
				)
				(justify left bottom)
				(hide yes)
			)
		)
		(property "Datasheet" "http://www.kingbright.com/attachments/file/psearch//000/00/00/KP-1608CGCK(Ver.23B).pdf"
			(at 135.89 167.64 0)
			(effects
				(font
					(size 1.27 1.27)
					(thickness 0.15)
				)
				(justify left bottom)
				(hide yes)
			)
		)
		(property "Description" ""
			(at 158.75 154.94 0)
			(effects
				(font
					(size 1.27 1.27)
				)
			)
		)
		(property "MPN" "KP-1608CGCK"
			(at 135.89 170.18 0)
			(effects
				(font
					(size 1.27 1.27)
					(thickness 0.15)
				)
				(justify left bottom)
				(hide yes)
			)
		)
		(property "Manufacturer" "Kingbright"
			(at 135.89 172.72 0)
			(effects
				(font
					(size 1.27 1.27)
					(thickness 0.15)
				)
				(justify left bottom)
				(hide yes)
			)
		)
		(property "Author" "Antmicro"
			(at 135.89 175.26 0)
			(effects
				(font
					(size 1.27 1.27)
					(thickness 0.15)
				)
				(justify left bottom)
				(hide yes)
			)
		)
		(property "License" "Apache-2.0"
			(at 135.89 177.8 0)
			(effects
				(font
					(size 1.27 1.27)
					(thickness 0.15)
				)
				(justify left bottom)
				(hide yes)
			)
		)
		(property "Color" "Green"
			(at 154.94 149.86 0)
			(effects
				(font
					(size 1.27 1.27)
				)
			)
		)
		(pin "1"
		)
		(pin "2"
		)
		(instances
			(project "k410t-devboard"
				(path ""
					(reference "D22")
					(unit 1)
				)
			)
		)
	)
	(symbol
		(lib_id "antmicroTVSDiodes:TPD4E05U06QDQARQ1")
		(at 292.1 229.87 0)
		(mirror y)
		(unit 1)
		(exclude_from_sim no)
		(in_bom yes)
		(on_board yes)
		(dnp no)
		(fields_autoplaced yes)
		(property "Reference" "U46"
			(at 286.385 222.25 0)
			(effects
				(font
					(size 1.27 1.27)
				)
			)
		)
		(property "Value" "TPD4E05U06QDQARQ1"
			(at 286.385 242.57 0)
			(effects
				(font
					(size 1.27 1.27)
					(thickness 0.15)
				)
				(hide yes)
			)
		)
		(property "Footprint" "antmicro-footprints:USON-10_2.5x1mm_P0.5mm"
			(at 267.97 234.95 0)
			(effects
				(font
					(size 1.27 1.27)
					(thickness 0.15)
				)
				(justify left bottom)
				(hide yes)
			)
		)
		(property "Datasheet" "https://www.ti.com/lit/ds/symlink/tpd4e05u06-q1.pdf?HQS=dis-mous-null-mousermode-dsf-pf-null-wwe&ts=1663591265741&ref_url=https%253A%252F%252Fwww.mouser.com%252F"
			(at 267.97 237.49 0)
			(effects
				(font
					(size 1.27 1.27)
					(thickness 0.15)
				)
				(justify left bottom)
				(hide yes)
			)
		)
		(property "Description" ""
			(at 292.1 229.87 0)
			(effects
				(font
					(size 1.27 1.27)
				)
			)
		)
		(property "Manufacturer" "Texas Instruments"
			(at 267.97 240.03 0)
			(effects
				(font
					(size 1.27 1.27)
					(thickness 0.15)
				)
				(justify left bottom)
				(hide yes)
			)
		)
		(property "MPN" "TPD4E05U06QDQARQ1"
			(at 286.385 224.79 0)
			(effects
				(font
					(size 1.27 1.27)
					(thickness 0.15)
				)
			)
		)
		(property "Author" "Antmicro"
			(at 267.97 245.11 0)
			(effects
				(font
					(size 1.27 1.27)
					(thickness 0.15)
				)
				(justify left bottom)
				(hide yes)
			)
		)
		(property "License" "Apache-2.0"
			(at 267.97 247.65 0)
			(effects
				(font
					(size 1.27 1.27)
					(thickness 0.15)
				)
				(justify left bottom)
				(hide yes)
			)
		)
		(pin "1"
		)
		(pin "10"
		)
		(pin "2"
		)
		(pin "3"
		)
		(pin "4"
		)
		(pin "5"
		)
		(pin "6"
		)
		(pin "7"
		)
		(pin "8"
		)
		(pin "9"
		)
		(instances
			(project "k410t-devboard"
				(path ""
					(reference "U46")
					(unit 1)
				)
			)
		)
	)
	(symbol
		(lib_id "antmicropower:+3.3V")
		(at 132.08 151.13 0)
		(unit 1)
		(exclude_from_sim no)
		(in_bom yes)
		(on_board yes)
		(dnp no)
		(fields_autoplaced yes)
		(property "Reference" "#PWR0151"
			(at 132.08 154.94 0)
			(effects
				(font
					(size 1.27 1.27)
				)
				(hide yes)
			)
		)
		(property "Value" "+3V3"
			(at 132.08 147.574 0)
			(effects
				(font
					(size 1.27 1.27)
				)
			)
		)
		(property "Footprint" ""
			(at 132.08 151.13 0)
			(effects
				(font
					(size 1.27 1.27)
				)
				(hide yes)
			)
		)
		(property "Datasheet" ""
			(at 132.08 151.13 0)
			(effects
				(font
					(size 1.27 1.27)
				)
				(hide yes)
			)
		)
		(property "Description" ""
			(at 132.08 151.13 0)
			(effects
				(font
					(size 1.27 1.27)
				)
			)
		)
		(pin "1"
		)
		(instances
			(project "k410t-devboard"
				(path ""
					(reference "#PWR0151")
					(unit 1)
				)
			)
		)
	)
	(symbol
		(lib_id "antmicropower:GND")
		(at 198.12 184.15 0)
		(unit 1)
		(exclude_from_sim no)
		(in_bom yes)
		(on_board yes)
		(dnp no)
		(property "Reference" "#PWR0179"
			(at 198.12 190.5 0)
			(effects
				(font
					(size 1.27 1.27)
				)
				(hide yes)
			)
		)
		(property "Value" "GND"
			(at 198.12 187.96 0)
			(effects
				(font
					(size 1.27 1.27)
				)
			)
		)
		(property "Footprint" ""
			(at 207.01 191.77 0)
			(effects
				(font
					(size 1.27 1.27)
					(thickness 0.15)
				)
				(justify left bottom)
				(hide yes)
			)
		)
		(property "Datasheet" ""
			(at 207.01 196.85 0)
			(effects
				(font
					(size 1.27 1.27)
					(thickness 0.15)
				)
				(justify left bottom)
				(hide yes)
			)
		)
		(property "Description" ""
			(at 198.12 184.15 0)
			(effects
				(font
					(size 1.27 1.27)
				)
			)
		)
		(property "Author" "Antmicro"
			(at 207.01 191.77 0)
			(effects
				(font
					(size 1.27 1.27)
					(thickness 0.15)
				)
				(justify left bottom)
				(hide yes)
			)
		)
		(property "License" "Apache-2.0"
			(at 207.01 194.31 0)
			(effects
				(font
					(size 1.27 1.27)
					(thickness 0.15)
				)
				(justify left bottom)
				(hide yes)
			)
		)
		(pin "1"
		)
		(instances
			(project "k410t-devboard"
				(path ""
					(reference "#PWR0179")
					(unit 1)
				)
			)
		)
	)
	(symbol
		(lib_id "antmicropower:GND")
		(at 198.12 165.1 0)
		(unit 1)
		(exclude_from_sim no)
		(in_bom yes)
		(on_board yes)
		(dnp no)
		(property "Reference" "#PWR0178"
			(at 198.12 171.45 0)
			(effects
				(font
					(size 1.27 1.27)
				)
				(hide yes)
			)
		)
		(property "Value" "GND"
			(at 198.12 168.91 0)
			(effects
				(font
					(size 1.27 1.27)
				)
			)
		)
		(property "Footprint" ""
			(at 207.01 172.72 0)
			(effects
				(font
					(size 1.27 1.27)
					(thickness 0.15)
				)
				(justify left bottom)
				(hide yes)
			)
		)
		(property "Datasheet" ""
			(at 207.01 177.8 0)
			(effects
				(font
					(size 1.27 1.27)
					(thickness 0.15)
				)
				(justify left bottom)
				(hide yes)
			)
		)
		(property "Description" ""
			(at 198.12 165.1 0)
			(effects
				(font
					(size 1.27 1.27)
				)
			)
		)
		(property "Author" "Antmicro"
			(at 207.01 172.72 0)
			(effects
				(font
					(size 1.27 1.27)
					(thickness 0.15)
				)
				(justify left bottom)
				(hide yes)
			)
		)
		(property "License" "Apache-2.0"
			(at 207.01 175.26 0)
			(effects
				(font
					(size 1.27 1.27)
					(thickness 0.15)
				)
				(justify left bottom)
				(hide yes)
			)
		)
		(pin "1"
		)
		(instances
			(project "k410t-devboard"
				(path ""
					(reference "#PWR0178")
					(unit 1)
				)
			)
		)
	)
	(symbol
		(lib_id "antmicroResistors0402:R_100R_0402")
		(at 279.4 40.64 180)
		(unit 1)
		(exclude_from_sim no)
		(in_bom yes)
		(on_board yes)
		(dnp no)
		(property "Reference" "R136"
			(at 281.94 39.37 0)
			(effects
				(font
					(size 1.27 1.27)
				)
			)
		)
		(property "Value" "R_100R_0402"
			(at 259.08 27.94 0)
			(effects
				(font
					(size 1.27 1.27)
					(thickness 0.15)
				)
				(justify left bottom)
				(hide yes)
			)
		)
		(property "Footprint" "antmicro-footprints:R_0402_1005Metric"
			(at 259.08 25.4 0)
			(effects
				(font
					(size 1.27 1.27)
					(thickness 0.15)
				)
				(justify left bottom)
				(hide yes)
			)
		)
		(property "Datasheet" "https://www.bourns.com/docs/product-datasheets/cr.pdf"
			(at 259.08 22.86 0)
			(effects
				(font
					(size 1.27 1.27)
					(thickness 0.15)
				)
				(justify left bottom)
				(hide yes)
			)
		)
		(property "Description" ""
			(at 279.4 40.64 0)
			(effects
				(font
					(size 1.27 1.27)
				)
			)
		)
		(property "Manufacturer" "Bourns"
			(at 259.08 17.78 0)
			(effects
				(font
					(size 1.27 1.27)
					(thickness 0.15)
				)
				(justify left bottom)
				(hide yes)
			)
		)
		(property "MPN" "CR0402-FX-1000GLF"
			(at 259.08 20.32 0)
			(effects
				(font
					(size 1.27 1.27)
					(thickness 0.15)
				)
				(justify left bottom)
				(hide yes)
			)
		)
		(property "Val" "100R"
			(at 271.78 39.37 0)
			(effects
				(font
					(size 1.27 1.27)
					(thickness 0.15)
				)
			)
		)
		(property "License" "Apache-2.0"
			(at 259.08 15.24 0)
			(effects
				(font
					(size 1.27 1.27)
					(thickness 0.15)
				)
				(justify left bottom)
				(hide yes)
			)
		)
		(property "Author" "Antmicro"
			(at 259.08 12.7 0)
			(effects
				(font
					(size 1.27 1.27)
					(thickness 0.15)
				)
				(justify left bottom)
				(hide yes)
			)
		)
		(property "Tolerance" "1%"
			(at 259.08 30.48 0)
			(effects
				(font
					(size 1.27 1.27)
				)
				(justify left bottom)
				(hide yes)
			)
		)
		(pin "1"
		)
		(pin "2"
		)
		(instances
			(project "k410t-devboard"
				(path ""
					(reference "R136")
					(unit 1)
				)
			)
		)
	)
	(symbol
		(lib_id "antmicropower:GND")
		(at 123.19 274.32 0)
		(unit 1)
		(exclude_from_sim no)
		(in_bom yes)
		(on_board yes)
		(dnp no)
		(property "Reference" "#PWR0159"
			(at 123.19 280.67 0)
			(effects
				(font
					(size 1.27 1.27)
				)
				(hide yes)
			)
		)
		(property "Value" "GND"
			(at 123.19 278.13 0)
			(effects
				(font
					(size 1.27 1.27)
				)
			)
		)
		(property "Footprint" ""
			(at 132.08 281.94 0)
			(effects
				(font
					(size 1.27 1.27)
					(thickness 0.15)
				)
				(justify left bottom)
				(hide yes)
			)
		)
		(property "Datasheet" ""
			(at 132.08 287.02 0)
			(effects
				(font
					(size 1.27 1.27)
					(thickness 0.15)
				)
				(justify left bottom)
				(hide yes)
			)
		)
		(property "Description" ""
			(at 123.19 274.32 0)
			(effects
				(font
					(size 1.27 1.27)
				)
			)
		)
		(property "Author" "Antmicro"
			(at 132.08 281.94 0)
			(effects
				(font
					(size 1.27 1.27)
					(thickness 0.15)
				)
				(justify left bottom)
				(hide yes)
			)
		)
		(property "License" "Apache-2.0"
			(at 132.08 284.48 0)
			(effects
				(font
					(size 1.27 1.27)
					(thickness 0.15)
				)
				(justify left bottom)
				(hide yes)
			)
		)
		(pin "1"
		)
		(instances
			(project "k410t-devboard"
				(path ""
					(reference "#PWR0159")
					(unit 1)
				)
			)
		)
	)
	(symbol
		(lib_id "antmicropower:GND")
		(at 115.57 165.1 0)
		(unit 1)
		(exclude_from_sim no)
		(in_bom yes)
		(on_board yes)
		(dnp no)
		(property "Reference" "#PWR0150"
			(at 115.57 171.45 0)
			(effects
				(font
					(size 1.27 1.27)
				)
				(hide yes)
			)
		)
		(property "Value" "GND"
			(at 115.57 168.91 0)
			(effects
				(font
					(size 1.27 1.27)
				)
			)
		)
		(property "Footprint" ""
			(at 124.46 172.72 0)
			(effects
				(font
					(size 1.27 1.27)
					(thickness 0.15)
				)
				(justify left bottom)
				(hide yes)
			)
		)
		(property "Datasheet" ""
			(at 124.46 177.8 0)
			(effects
				(font
					(size 1.27 1.27)
					(thickness 0.15)
				)
				(justify left bottom)
				(hide yes)
			)
		)
		(property "Description" ""
			(at 115.57 165.1 0)
			(effects
				(font
					(size 1.27 1.27)
				)
			)
		)
		(property "Author" "Antmicro"
			(at 124.46 172.72 0)
			(effects
				(font
					(size 1.27 1.27)
					(thickness 0.15)
				)
				(justify left bottom)
				(hide yes)
			)
		)
		(property "License" "Apache-2.0"
			(at 124.46 175.26 0)
			(effects
				(font
					(size 1.27 1.27)
					(thickness 0.15)
				)
				(justify left bottom)
				(hide yes)
			)
		)
		(pin "1"
		)
		(instances
			(project "k410t-devboard"
				(path ""
					(reference "#PWR0150")
					(unit 1)
				)
			)
		)
	)
	(symbol
		(lib_id "antmicroResistors0402:R_100R_0402")
		(at 87.63 30.48 180)
		(unit 1)
		(exclude_from_sim no)
		(in_bom yes)
		(on_board yes)
		(dnp no)
		(property "Reference" "R112"
			(at 90.17 29.21 0)
			(effects
				(font
					(size 1.27 1.27)
				)
			)
		)
		(property "Value" "R_100R_0402"
			(at 67.31 17.78 0)
			(effects
				(font
					(size 1.27 1.27)
					(thickness 0.15)
				)
				(justify left bottom)
				(hide yes)
			)
		)
		(property "Footprint" "antmicro-footprints:R_0402_1005Metric"
			(at 67.31 15.24 0)
			(effects
				(font
					(size 1.27 1.27)
					(thickness 0.15)
				)
				(justify left bottom)
				(hide yes)
			)
		)
		(property "Datasheet" "https://www.bourns.com/docs/product-datasheets/cr.pdf"
			(at 67.31 12.7 0)
			(effects
				(font
					(size 1.27 1.27)
					(thickness 0.15)
				)
				(justify left bottom)
				(hide yes)
			)
		)
		(property "Description" ""
			(at 87.63 30.48 0)
			(effects
				(font
					(size 1.27 1.27)
				)
			)
		)
		(property "Manufacturer" "Bourns"
			(at 67.31 7.62 0)
			(effects
				(font
					(size 1.27 1.27)
					(thickness 0.15)
				)
				(justify left bottom)
				(hide yes)
			)
		)
		(property "MPN" "CR0402-FX-1000GLF"
			(at 67.31 10.16 0)
			(effects
				(font
					(size 1.27 1.27)
					(thickness 0.15)
				)
				(justify left bottom)
				(hide yes)
			)
		)
		(property "Val" "100R"
			(at 80.01 29.21 0)
			(effects
				(font
					(size 1.27 1.27)
					(thickness 0.15)
				)
			)
		)
		(property "License" "Apache-2.0"
			(at 67.31 5.08 0)
			(effects
				(font
					(size 1.27 1.27)
					(thickness 0.15)
				)
				(justify left bottom)
				(hide yes)
			)
		)
		(property "Author" "Antmicro"
			(at 67.31 2.54 0)
			(effects
				(font
					(size 1.27 1.27)
					(thickness 0.15)
				)
				(justify left bottom)
				(hide yes)
			)
		)
		(property "Tolerance" "1%"
			(at 67.31 20.32 0)
			(effects
				(font
					(size 1.27 1.27)
				)
				(justify left bottom)
				(hide yes)
			)
		)
		(pin "1"
		)
		(pin "2"
		)
		(instances
			(project "k410t-devboard"
				(path ""
					(reference "R112")
					(unit 1)
				)
			)
		)
	)
	(symbol
		(lib_id "antmicroResistors0402:R_10k_0402")
		(at 302.26 83.82 270)
		(unit 1)
		(exclude_from_sim no)
		(in_bom yes)
		(on_board yes)
		(dnp no)
		(fields_autoplaced yes)
		(property "Reference" "R140"
			(at 304.165 85.0899 90)
			(effects
				(font
					(size 1.27 1.27)
				)
				(justify left)
			)
		)
		(property "Value" "R_10k_0402"
			(at 289.56 104.14 0)
			(effects
				(font
					(size 1.27 1.27)
					(thickness 0.15)
				)
				(justify left bottom)
				(hide yes)
			)
		)
		(property "Footprint" "antmicro-footprints:R_0402_1005Metric"
			(at 287.02 104.14 0)
			(effects
				(font
					(size 1.27 1.27)
					(thickness 0.15)
				)
				(justify left bottom)
				(hide yes)
			)
		)
		(property "Datasheet" "https://www.bourns.com/docs/product-datasheets/cr.pdf"
			(at 284.48 104.14 0)
			(effects
				(font
					(size 1.27 1.27)
					(thickness 0.15)
				)
				(justify left bottom)
				(hide yes)
			)
		)
		(property "Description" ""
			(at 302.26 83.82 0)
			(effects
				(font
					(size 1.27 1.27)
				)
			)
		)
		(property "Manufacturer" "Bourns"
			(at 279.4 104.14 0)
			(effects
				(font
					(size 1.27 1.27)
					(thickness 0.15)
				)
				(justify left bottom)
				(hide yes)
			)
		)
		(property "MPN" "CR0402-FX-1002GLF"
			(at 281.94 104.14 0)
			(effects
				(font
					(size 1.27 1.27)
					(thickness 0.15)
				)
				(justify left bottom)
				(hide yes)
			)
		)
		(property "Val" "10k"
			(at 304.165 87.6299 90)
			(effects
				(font
					(size 1.27 1.27)
					(thickness 0.15)
				)
				(justify left)
			)
		)
		(property "License" "Apache-2.0"
			(at 276.86 104.14 0)
			(effects
				(font
					(size 1.27 1.27)
					(thickness 0.15)
				)
				(justify left bottom)
				(hide yes)
			)
		)
		(property "Author" "Antmicro"
			(at 274.32 104.14 0)
			(effects
				(font
					(size 1.27 1.27)
					(thickness 0.15)
				)
				(justify left bottom)
				(hide yes)
			)
		)
		(property "Tolerance" "1%"
			(at 292.1 104.14 0)
			(effects
				(font
					(size 1.27 1.27)
				)
				(justify left bottom)
				(hide yes)
			)
		)
		(pin "1"
		)
		(pin "2"
		)
		(instances
			(project "k410t-devboard"
				(path ""
					(reference "R140")
					(unit 1)
				)
			)
		)
	)
	(symbol
		(lib_id "antmicroResistors0402:R_0R_0402")
		(at 57.15 273.05 0)
		(unit 1)
		(exclude_from_sim no)
		(in_bom yes)
		(on_board yes)
		(dnp no)
		(property "Reference" "R19"
			(at 64.135 271.78 0)
			(effects
				(font
					(size 1.27 1.27)
				)
			)
		)
		(property "Value" "R_0R_0402"
			(at 77.47 285.75 0)
			(effects
				(font
					(size 1.27 1.27)
					(thickness 0.15)
				)
				(justify left bottom)
				(hide yes)
			)
		)
		(property "Footprint" "antmicro-footprints:R_0402_1005Metric"
			(at 77.47 288.29 0)
			(effects
				(font
					(size 1.27 1.27)
					(thickness 0.15)
				)
				(justify left bottom)
				(hide yes)
			)
		)
		(property "Datasheet" "https://industrial.panasonic.com/cdbs/www-data/pdf/RDA0000/AOA0000C301.pdf"
			(at 77.47 290.83 0)
			(effects
				(font
					(size 1.27 1.27)
					(thickness 0.15)
				)
				(justify left bottom)
				(hide yes)
			)
		)
		(property "Description" ""
			(at 57.15 273.05 0)
			(effects
				(font
					(size 1.27 1.27)
				)
			)
		)
		(property "Manufacturer" "Panasonic"
			(at 77.47 295.91 0)
			(effects
				(font
					(size 1.27 1.27)
					(thickness 0.15)
				)
				(justify left bottom)
				(hide yes)
			)
		)
		(property "MPN" "ERJ2GE0R00X"
			(at 77.47 293.37 0)
			(effects
				(font
					(size 1.27 1.27)
					(thickness 0.15)
				)
				(justify left bottom)
				(hide yes)
			)
		)
		(property "Val" "0R"
			(at 55.88 271.78 0)
			(effects
				(font
					(size 1.27 1.27)
					(thickness 0.15)
				)
			)
		)
		(property "License" "Apache-2.0"
			(at 77.47 298.45 0)
			(effects
				(font
					(size 1.27 1.27)
					(thickness 0.15)
				)
				(justify left bottom)
				(hide yes)
			)
		)
		(property "Author" "Antmicro"
			(at 77.47 300.99 0)
			(effects
				(font
					(size 1.27 1.27)
					(thickness 0.15)
				)
				(justify left bottom)
				(hide yes)
			)
		)
		(property "Tolerance" "~"
			(at 77.47 283.21 0)
			(effects
				(font
					(size 1.27 1.27)
				)
				(justify left bottom)
				(hide yes)
			)
		)
		(property "Current" "1A"
			(at 59.69 269.24 0)
			(effects
				(font
					(size 1.27 1.27)
					(thickness 0.15)
				)
				(hide yes)
			)
		)
		(pin "1"
		)
		(pin "2"
		)
		(instances
			(project "k410t-devboard"
				(path ""
					(reference "R19")
					(unit 1)
				)
			)
		)
	)
	(symbol
		(lib_id "antmicropower:+1V8")
		(at 377.19 81.28 0)
		(unit 1)
		(exclude_from_sim no)
		(in_bom yes)
		(on_board yes)
		(dnp no)
		(fields_autoplaced yes)
		(property "Reference" "#PWR0174"
			(at 377.19 85.09 0)
			(effects
				(font
					(size 1.27 1.27)
				)
				(hide yes)
			)
		)
		(property "Value" "+1V8"
			(at 377.19 77.724 0)
			(effects
				(font
					(size 1.27 1.27)
				)
			)
		)
		(property "Footprint" ""
			(at 392.43 88.9 0)
			(effects
				(font
					(size 1.27 1.27)
					(thickness 0.15)
				)
				(justify left bottom)
				(hide yes)
			)
		)
		(property "Datasheet" ""
			(at 392.43 91.44 0)
			(effects
				(font
					(size 1.27 1.27)
					(thickness 0.15)
				)
				(justify left bottom)
				(hide yes)
			)
		)
		(property "Description" ""
			(at 377.19 81.28 0)
			(effects
				(font
					(size 1.27 1.27)
				)
			)
		)
		(property "Author" "Antmicro"
			(at 392.43 88.9 0)
			(effects
				(font
					(size 1.27 1.27)
					(thickness 0.15)
				)
				(justify left bottom)
				(hide yes)
			)
		)
		(property "License" "Apache-2.0"
			(at 392.43 91.44 0)
			(effects
				(font
					(size 1.27 1.27)
					(thickness 0.15)
				)
				(justify left bottom)
				(hide yes)
			)
		)
		(pin "1"
		)
		(instances
			(project "k410t-devboard"
				(path ""
					(reference "#PWR0174")
					(unit 1)
				)
			)
		)
	)
	(symbol
		(lib_id "antmicroLEDIndicationDiscrete:LED_G_0603_KP-1608CGCK")
		(at 76.2 173.99 0)
		(mirror y)
		(unit 1)
		(exclude_from_sim no)
		(in_bom yes)
		(on_board yes)
		(dnp no)
		(property "Reference" "D19"
			(at 72.39 166.37 0)
			(effects
				(font
					(size 1.27 1.27)
				)
			)
		)
		(property "Value" "LED_G_0603_KP-1608CGCK"
			(at 72.39 177.165 0)
			(effects
				(font
					(size 1.27 1.27)
					(thickness 0.15)
				)
				(hide yes)
			)
		)
		(property "Footprint" "antmicro-footprints:LED_0603_1608Metric_G"
			(at 53.34 184.15 0)
			(effects
				(font
					(size 1.27 1.27)
					(thickness 0.15)
				)
				(justify left bottom)
				(hide yes)
			)
		)
		(property "Datasheet" "http://www.kingbright.com/attachments/file/psearch//000/00/00/KP-1608CGCK(Ver.23B).pdf"
			(at 53.34 186.69 0)
			(effects
				(font
					(size 1.27 1.27)
					(thickness 0.15)
				)
				(justify left bottom)
				(hide yes)
			)
		)
		(property "Description" ""
			(at 76.2 173.99 0)
			(effects
				(font
					(size 1.27 1.27)
				)
			)
		)
		(property "MPN" "KP-1608CGCK"
			(at 53.34 189.23 0)
			(effects
				(font
					(size 1.27 1.27)
					(thickness 0.15)
				)
				(justify left bottom)
				(hide yes)
			)
		)
		(property "Manufacturer" "Kingbright"
			(at 53.34 191.77 0)
			(effects
				(font
					(size 1.27 1.27)
					(thickness 0.15)
				)
				(justify left bottom)
				(hide yes)
			)
		)
		(property "Author" "Antmicro"
			(at 53.34 194.31 0)
			(effects
				(font
					(size 1.27 1.27)
					(thickness 0.15)
				)
				(justify left bottom)
				(hide yes)
			)
		)
		(property "License" "Apache-2.0"
			(at 53.34 196.85 0)
			(effects
				(font
					(size 1.27 1.27)
					(thickness 0.15)
				)
				(justify left bottom)
				(hide yes)
			)
		)
		(property "Color" "Green"
			(at 72.39 168.91 0)
			(effects
				(font
					(size 1.27 1.27)
				)
			)
		)
		(pin "1"
		)
		(pin "2"
		)
		(instances
			(project "k410t-devboard"
				(path ""
					(reference "D19")
					(unit 1)
				)
			)
		)
	)
)
